FILE_TYPE = MACRO_DRAWING;
SET COLOR_WIRE YELLOW;
SET COLOR_PROP ORANGE;
SET COLOR_DOT WHITE;
SET COLOR_ARC YELLOW;
SET COLOR_BODY GREEN;
SET COLOR_NOTE PURPLE;
SET PROP_DISPLAY VALUE;
SET PAGE_NUMBER P58;
FORCEADD GENOA_SP5..28
(-8575 3425);
FORCEPROP 1 LAST LOCATION U26
J 0
(-8975 6600);
DISPLAY 0.489362 (-8975 6600);
PAINT SKYBLUE (-8975 6600);
FORCEPROP 0 LAST $SEC 28
J 0
(-8950 6825);
DISPLAY 0.680851 (-8950 6825);
PAINT MONO (-8950 6825);
DISPLAY INVISIBLE (-8950 6825);
FORCEPROP 0 LAST CDS_SEC 28
J 0
(-8950 6825);
DISPLAY 1.021277 (-8950 6825);
DISPLAY INVISIBLE (-8950 6825);
FORCEPROP 0 LASTPIN (-9125 6375) $PN A3
J 2
(-9135 6385);
DISPLAY 0.489362 (-9135 6385);
PAINT MONO (-9135 6385);
FORCEPROP 0 LASTPIN (-9125 6325) $PN A9
J 2
(-9135 6335);
DISPLAY 0.489362 (-9135 6335);
PAINT MONO (-9135 6335);
FORCEPROP 0 LASTPIN (-9125 6275) $PN A15
J 2
(-9135 6285);
DISPLAY 0.489362 (-9135 6285);
PAINT MONO (-9135 6285);
FORCEPROP 0 LASTPIN (-9125 6225) $PN A21
J 2
(-9135 6235);
DISPLAY 0.489362 (-9135 6235);
PAINT MONO (-9135 6235);
FORCEPROP 0 LASTPIN (-9125 6175) $PN A27
J 2
(-9135 6185);
DISPLAY 0.489362 (-9135 6185);
PAINT MONO (-9135 6185);
FORCEPROP 0 LASTPIN (-9125 6125) $PN A43
J 2
(-9135 6135);
DISPLAY 0.489362 (-9135 6135);
PAINT MONO (-9135 6135);
FORCEPROP 0 LASTPIN (-9125 6075) $PN A44
J 2
(-9135 6085);
DISPLAY 0.489362 (-9135 6085);
PAINT MONO (-9135 6085);
FORCEPROP 0 LASTPIN (-9125 6025) $PN A47
J 2
(-9135 6035);
DISPLAY 0.489362 (-9135 6035);
PAINT MONO (-9135 6035);
FORCEPROP 0 LASTPIN (-9125 5975) $PN A49
J 2
(-9135 5985);
DISPLAY 0.489362 (-9135 5985);
PAINT MONO (-9135 5985);
FORCEPROP 0 LASTPIN (-9125 5925) $PN A53
J 2
(-9135 5935);
DISPLAY 0.489362 (-9135 5935);
PAINT MONO (-9135 5935);
FORCEPROP 0 LASTPIN (-9125 5875) $PN A61
J 2
(-9135 5885);
DISPLAY 0.489362 (-9135 5885);
PAINT MONO (-9135 5885);
FORCEPROP 0 LASTPIN (-9125 5825) $PN A67
J 2
(-9135 5835);
DISPLAY 0.489362 (-9135 5835);
PAINT MONO (-9135 5835);
FORCEPROP 0 LASTPIN (-9125 5775) $PN A72
J 2
(-9135 5785);
DISPLAY 0.489362 (-9135 5785);
PAINT MONO (-9135 5785);
FORCEPROP 0 LASTPIN (-9125 5725) $PN A73
J 2
(-9135 5735);
DISPLAY 0.489362 (-9135 5735);
PAINT MONO (-9135 5735);
FORCEPROP 0 LASTPIN (-9125 5675) $PN B7
J 2
(-9135 5685);
DISPLAY 0.489362 (-9135 5685);
PAINT MONO (-9135 5685);
FORCEPROP 0 LASTPIN (-9125 5625) $PN B8
J 2
(-9135 5635);
DISPLAY 0.489362 (-9135 5635);
PAINT MONO (-9135 5635);
FORCEPROP 0 LASTPIN (-9125 5575) $PN B10
J 2
(-9135 5585);
DISPLAY 0.489362 (-9135 5585);
PAINT MONO (-9135 5585);
FORCEPROP 0 LASTPIN (-9125 5525) $PN B11
J 2
(-9135 5535);
DISPLAY 0.489362 (-9135 5535);
PAINT MONO (-9135 5535);
FORCEPROP 0 LASTPIN (-9125 5475) $PN B13
J 2
(-9135 5485);
DISPLAY 0.489362 (-9135 5485);
PAINT MONO (-9135 5485);
FORCEPROP 0 LASTPIN (-9125 5425) $PN B18
J 2
(-9135 5435);
DISPLAY 0.489362 (-9135 5435);
PAINT MONO (-9135 5435);
FORCEPROP 0 LASTPIN (-9125 5375) $PN B24
J 2
(-9135 5385);
DISPLAY 0.489362 (-9135 5385);
PAINT MONO (-9135 5385);
FORCEPROP 0 LASTPIN (-9125 5325) $PN B27
J 2
(-9135 5335);
DISPLAY 0.489362 (-9135 5335);
PAINT MONO (-9135 5335);
FORCEPROP 0 LASTPIN (-9125 5275) $PN B30
J 2
(-9135 5285);
DISPLAY 0.489362 (-9135 5285);
PAINT MONO (-9135 5285);
FORCEPROP 0 LASTPIN (-9125 5225) $PN B33
J 2
(-9135 5235);
DISPLAY 0.489362 (-9135 5235);
PAINT MONO (-9135 5235);
FORCEPROP 0 LASTPIN (-9125 5175) $PN B37
J 2
(-9135 5185);
DISPLAY 0.489362 (-9135 5185);
PAINT MONO (-9135 5185);
FORCEPROP 0 LASTPIN (-9125 5125) $PN B39
J 2
(-9135 5135);
DISPLAY 0.489362 (-9135 5135);
PAINT MONO (-9135 5135);
FORCEPROP 0 LASTPIN (-9125 5075) $PN B43
J 2
(-9135 5085);
DISPLAY 0.489362 (-9135 5085);
PAINT MONO (-9135 5085);
FORCEPROP 0 LASTPIN (-9125 5025) $PN B46
J 2
(-9135 5035);
DISPLAY 0.489362 (-9135 5035);
PAINT MONO (-9135 5035);
FORCEPROP 0 LASTPIN (-9125 4975) $PN B49
J 2
(-9135 4985);
DISPLAY 0.489362 (-9135 4985);
PAINT MONO (-9135 4985);
FORCEPROP 0 LASTPIN (-9125 4925) $PN B52
J 2
(-9135 4935);
DISPLAY 0.489362 (-9135 4935);
PAINT MONO (-9135 4935);
FORCEPROP 0 LASTPIN (-9125 4875) $PN B55
J 2
(-9135 4885);
DISPLAY 0.489362 (-9135 4885);
PAINT MONO (-9135 4885);
FORCEPROP 0 LASTPIN (-9125 4825) $PN B59
J 2
(-9135 4835);
DISPLAY 0.489362 (-9135 4835);
PAINT MONO (-9135 4835);
FORCEPROP 0 LASTPIN (-9125 4775) $PN B62
J 2
(-9135 4785);
DISPLAY 0.489362 (-9135 4785);
PAINT MONO (-9135 4785);
FORCEPROP 0 LASTPIN (-9125 4725) $PN B65
J 2
(-9135 4735);
DISPLAY 0.489362 (-9135 4735);
PAINT MONO (-9135 4735);
FORCEPROP 0 LASTPIN (-9125 4675) $PN B68
J 2
(-9135 4685);
DISPLAY 0.489362 (-9135 4685);
PAINT MONO (-9135 4685);
FORCEPROP 0 LASTPIN (-9125 4625) $PN B70
J 2
(-9135 4635);
DISPLAY 0.489362 (-9135 4635);
PAINT MONO (-9135 4635);
FORCEPROP 0 LASTPIN (-9125 4575) $PN C1
J 2
(-9135 4585);
DISPLAY 0.489362 (-9135 4585);
PAINT MONO (-9135 4585);
FORCEPROP 0 LASTPIN (-9125 4525) $PN C5
J 2
(-9135 4535);
DISPLAY 0.489362 (-9135 4535);
PAINT MONO (-9135 4535);
FORCEPROP 0 LASTPIN (-9125 4475) $PN C8
J 2
(-9135 4485);
DISPLAY 0.489362 (-9135 4485);
PAINT MONO (-9135 4485);
FORCEPROP 0 LASTPIN (-9125 4425) $PN C10
J 2
(-9135 4435);
DISPLAY 0.489362 (-9135 4435);
PAINT MONO (-9135 4435);
FORCEPROP 0 LASTPIN (-9125 4375) $PN C11
J 2
(-9135 4385);
DISPLAY 0.489362 (-9135 4385);
PAINT MONO (-9135 4385);
FORCEPROP 0 LASTPIN (-9125 4325) $PN C13
J 2
(-9135 4335);
DISPLAY 0.489362 (-9135 4335);
PAINT MONO (-9135 4335);
FORCEPROP 0 LASTPIN (-9125 4275) $PN C15
J 2
(-9135 4285);
DISPLAY 0.489362 (-9135 4285);
PAINT MONO (-9135 4285);
FORCEPROP 0 LASTPIN (-9125 4225) $PN C21
J 2
(-9135 4235);
DISPLAY 0.489362 (-9135 4235);
PAINT MONO (-9135 4235);
FORCEPROP 0 LASTPIN (-9125 4175) $PN C24
J 2
(-9135 4185);
DISPLAY 0.489362 (-9135 4185);
PAINT MONO (-9135 4185);
FORCEPROP 0 LASTPIN (-9125 4125) $PN C27
J 2
(-9135 4135);
DISPLAY 0.489362 (-9135 4135);
PAINT MONO (-9135 4135);
FORCEPROP 0 LASTPIN (-9125 4075) $PN C30
J 2
(-9135 4085);
DISPLAY 0.489362 (-9135 4085);
PAINT MONO (-9135 4085);
FORCEPROP 0 LASTPIN (-9125 4025) $PN C36
J 2
(-9135 4035);
DISPLAY 0.489362 (-9135 4035);
PAINT MONO (-9135 4035);
FORCEPROP 0 LASTPIN (-9125 3975) $PN C40
J 2
(-9135 3985);
DISPLAY 0.489362 (-9135 3985);
PAINT MONO (-9135 3985);
FORCEPROP 0 LASTPIN (-9125 3925) $PN C43
J 2
(-9135 3935);
DISPLAY 0.489362 (-9135 3935);
PAINT MONO (-9135 3935);
FORCEPROP 0 LASTPIN (-9125 3875) $PN C46
J 2
(-9135 3885);
DISPLAY 0.489362 (-9135 3885);
PAINT MONO (-9135 3885);
FORCEPROP 0 LASTPIN (-9125 3825) $PN C49
J 2
(-9135 3835);
DISPLAY 0.489362 (-9135 3835);
PAINT MONO (-9135 3835);
FORCEPROP 0 LASTPIN (-9125 3775) $PN C52
J 2
(-9135 3785);
DISPLAY 0.489362 (-9135 3785);
PAINT MONO (-9135 3785);
FORCEPROP 0 LASTPIN (-9125 3725) $PN C55
J 2
(-9135 3735);
DISPLAY 0.489362 (-9135 3735);
PAINT MONO (-9135 3735);
FORCEPROP 0 LASTPIN (-9125 3675) $PN C56
J 2
(-9135 3685);
DISPLAY 0.489362 (-9135 3685);
PAINT MONO (-9135 3685);
FORCEPROP 0 LASTPIN (-9125 3625) $PN C57
J 2
(-9135 3635);
DISPLAY 0.489362 (-9135 3635);
PAINT MONO (-9135 3635);
FORCEPROP 0 LASTPIN (-9125 3575) $PN C61
J 2
(-9135 3585);
DISPLAY 0.489362 (-9135 3585);
PAINT MONO (-9135 3585);
FORCEPROP 0 LASTPIN (-9125 3525) $PN C64
J 2
(-9135 3535);
DISPLAY 0.489362 (-9135 3535);
PAINT MONO (-9135 3535);
FORCEPROP 0 LASTPIN (-9125 3475) $PN C67
J 2
(-9135 3485);
DISPLAY 0.489362 (-9135 3485);
PAINT MONO (-9135 3485);
FORCEPROP 0 LASTPIN (-9125 3425) $PN C69
J 2
(-9135 3435);
DISPLAY 0.489362 (-9135 3435);
PAINT MONO (-9135 3435);
FORCEPROP 0 LASTPIN (-9125 3375) $PN C71
J 2
(-9135 3385);
DISPLAY 0.489362 (-9135 3385);
PAINT MONO (-9135 3385);
FORCEPROP 0 LASTPIN (-9125 3325) $PN C73
J 2
(-9135 3335);
DISPLAY 0.489362 (-9135 3335);
PAINT MONO (-9135 3335);
FORCEPROP 0 LASTPIN (-9125 3275) $PN C75
J 2
(-9135 3285);
DISPLAY 0.489362 (-9135 3285);
PAINT MONO (-9135 3285);
FORCEPROP 0 LASTPIN (-9125 3225) $PN D2
J 2
(-9135 3235);
DISPLAY 0.489362 (-9135 3235);
PAINT MONO (-9135 3235);
FORCEPROP 0 LASTPIN (-9125 3175) $PN D3
J 2
(-9135 3185);
DISPLAY 0.489362 (-9135 3185);
PAINT MONO (-9135 3185);
FORCEPROP 0 LASTPIN (-9125 3125) $PN D5
J 2
(-9135 3135);
DISPLAY 0.489362 (-9135 3135);
PAINT MONO (-9135 3135);
FORCEPROP 0 LASTPIN (-9125 3075) $PN D6
J 2
(-9135 3085);
DISPLAY 0.489362 (-9135 3085);
PAINT MONO (-9135 3085);
FORCEPROP 0 LASTPIN (-9125 3025) $PN D9
J 2
(-9135 3035);
DISPLAY 0.489362 (-9135 3035);
PAINT MONO (-9135 3035);
FORCEPROP 0 LASTPIN (-9125 2975) $PN D10
J 2
(-9135 2985);
DISPLAY 0.489362 (-9135 2985);
PAINT MONO (-9135 2985);
FORCEPROP 0 LASTPIN (-9125 2925) $PN D12
J 2
(-9135 2935);
DISPLAY 0.489362 (-9135 2935);
PAINT MONO (-9135 2935);
FORCEPROP 0 LASTPIN (-9125 2875) $PN D13
J 2
(-9135 2885);
DISPLAY 0.489362 (-9135 2885);
PAINT MONO (-9135 2885);
FORCEPROP 0 LASTPIN (-9125 2825) $PN D16
J 2
(-9135 2835);
DISPLAY 0.489362 (-9135 2835);
PAINT MONO (-9135 2835);
FORCEPROP 0 LASTPIN (-9125 2775) $PN D17
J 2
(-9135 2785);
DISPLAY 0.489362 (-9135 2785);
PAINT MONO (-9135 2785);
FORCEPROP 0 LASTPIN (-9125 2725) $PN D19
J 2
(-9135 2735);
DISPLAY 0.489362 (-9135 2735);
PAINT MONO (-9135 2735);
FORCEPROP 0 LASTPIN (-9125 2675) $PN D20
J 2
(-9135 2685);
DISPLAY 0.489362 (-9135 2685);
PAINT MONO (-9135 2685);
FORCEPROP 0 LASTPIN (-9125 2625) $PN D21
J 2
(-9135 2635);
DISPLAY 0.489362 (-9135 2635);
PAINT MONO (-9135 2635);
FORCEPROP 0 LASTPIN (-9125 2575) $PN D24
J 2
(-9135 2585);
DISPLAY 0.489362 (-9135 2585);
PAINT MONO (-9135 2585);
FORCEPROP 0 LASTPIN (-9125 2525) $PN D25
J 2
(-9135 2535);
DISPLAY 0.489362 (-9135 2535);
PAINT MONO (-9135 2535);
FORCEPROP 0 LASTPIN (-9125 2475) $PN D26
J 2
(-9135 2485);
DISPLAY 0.489362 (-9135 2485);
PAINT MONO (-9135 2485);
FORCEPROP 0 LASTPIN (-9125 2425) $PN D27
J 2
(-9135 2435);
DISPLAY 0.489362 (-9135 2435);
PAINT MONO (-9135 2435);
FORCEPROP 0 LASTPIN (-9125 2375) $PN D28
J 2
(-9135 2385);
DISPLAY 0.489362 (-9135 2385);
PAINT MONO (-9135 2385);
FORCEPROP 0 LASTPIN (-9125 2325) $PN D29
J 2
(-9135 2335);
DISPLAY 0.489362 (-9135 2335);
PAINT MONO (-9135 2335);
FORCEPROP 0 LASTPIN (-9125 2275) $PN D30
J 2
(-9135 2285);
DISPLAY 0.489362 (-9135 2285);
PAINT MONO (-9135 2285);
FORCEPROP 0 LASTPIN (-9125 2225) $PN D31
J 2
(-9135 2235);
DISPLAY 0.489362 (-9135 2235);
PAINT MONO (-9135 2235);
FORCEPROP 0 LASTPIN (-9125 2175) $PN D35
J 2
(-9135 2185);
DISPLAY 0.489362 (-9135 2185);
PAINT MONO (-9135 2185);
FORCEPROP 0 LASTPIN (-9125 2125) $PN D37
J 2
(-9135 2135);
DISPLAY 0.489362 (-9135 2135);
PAINT MONO (-9135 2135);
FORCEPROP 0 LASTPIN (-9125 2075) $PN D39
J 2
(-9135 2085);
DISPLAY 0.489362 (-9135 2085);
PAINT MONO (-9135 2085);
FORCEPROP 0 LASTPIN (-9125 2025) $PN D40
J 2
(-9135 2035);
DISPLAY 0.489362 (-9135 2035);
PAINT MONO (-9135 2035);
FORCEPROP 0 LASTPIN (-9125 1975) $PN D41
J 2
(-9135 1985);
DISPLAY 0.489362 (-9135 1985);
PAINT MONO (-9135 1985);
FORCEPROP 0 LASTPIN (-9125 1925) $PN D42
J 2
(-9135 1935);
DISPLAY 0.489362 (-9135 1935);
PAINT MONO (-9135 1935);
FORCEPROP 0 LASTPIN (-9125 1875) $PN D43
J 2
(-9135 1885);
DISPLAY 0.489362 (-9135 1885);
PAINT MONO (-9135 1885);
FORCEPROP 0 LASTPIN (-9125 1825) $PN D44
J 2
(-9135 1835);
DISPLAY 0.489362 (-9135 1835);
PAINT MONO (-9135 1835);
FORCEPROP 0 LASTPIN (-9125 1775) $PN D45
J 2
(-9135 1785);
DISPLAY 0.489362 (-9135 1785);
PAINT MONO (-9135 1785);
FORCEPROP 0 LASTPIN (-9125 1725) $PN D46
J 2
(-9135 1735);
DISPLAY 0.489362 (-9135 1735);
PAINT MONO (-9135 1735);
FORCEPROP 0 LASTPIN (-9125 1675) $PN D47
J 2
(-9135 1685);
DISPLAY 0.489362 (-9135 1685);
PAINT MONO (-9135 1685);
FORCEPROP 0 LASTPIN (-9125 1625) $PN D48
J 2
(-9135 1635);
DISPLAY 0.489362 (-9135 1635);
PAINT MONO (-9135 1635);
FORCEPROP 0 LASTPIN (-9125 1575) $PN D49
J 2
(-9135 1585);
DISPLAY 0.489362 (-9135 1585);
PAINT MONO (-9135 1585);
FORCEPROP 0 LASTPIN (-9125 1525) $PN D50
J 2
(-9135 1535);
DISPLAY 0.489362 (-9135 1535);
PAINT MONO (-9135 1535);
FORCEPROP 0 LASTPIN (-9125 1475) $PN D51
J 2
(-9135 1485);
DISPLAY 0.489362 (-9135 1485);
PAINT MONO (-9135 1485);
FORCEPROP 0 LASTPIN (-9125 1425) $PN D52
J 2
(-9135 1435);
DISPLAY 0.489362 (-9135 1435);
PAINT MONO (-9135 1435);
FORCEPROP 0 LASTPIN (-9125 1375) $PN D53
J 2
(-9135 1385);
DISPLAY 0.489362 (-9135 1385);
PAINT MONO (-9135 1385);
FORCEPROP 0 LASTPIN (-9125 1325) $PN D54
J 2
(-9135 1335);
DISPLAY 0.489362 (-9135 1335);
PAINT MONO (-9135 1335);
FORCEPROP 0 LASTPIN (-9125 1275) $PN D57
J 2
(-9135 1285);
DISPLAY 0.489362 (-9135 1285);
PAINT MONO (-9135 1285);
FORCEPROP 0 LASTPIN (-9125 1225) $PN D59
J 2
(-9135 1235);
DISPLAY 0.489362 (-9135 1235);
PAINT MONO (-9135 1235);
FORCEPROP 0 LASTPIN (-9125 1175) $PN D60
J 2
(-9135 1185);
DISPLAY 0.489362 (-9135 1185);
PAINT MONO (-9135 1185);
FORCEPROP 0 LASTPIN (-9125 1125) $PN D61
J 2
(-9135 1135);
DISPLAY 0.489362 (-9135 1135);
PAINT MONO (-9135 1135);
FORCEPROP 0 LASTPIN (-9125 1075) $PN D63
J 2
(-9135 1085);
DISPLAY 0.489362 (-9135 1085);
PAINT MONO (-9135 1085);
FORCEPROP 0 LASTPIN (-9125 1025) $PN D64
J 2
(-9135 1035);
DISPLAY 0.489362 (-9135 1035);
PAINT MONO (-9135 1035);
FORCEPROP 0 LASTPIN (-9125 975) $PN D66
J 2
(-9135 985);
DISPLAY 0.489362 (-9135 985);
PAINT MONO (-9135 985);
FORCEPROP 0 LASTPIN (-9125 925) $PN D67
J 2
(-9135 935);
DISPLAY 0.489362 (-9135 935);
PAINT MONO (-9135 935);
FORCEPROP 0 LASTPIN (-9125 875) $PN D70
J 2
(-9135 885);
DISPLAY 0.489362 (-9135 885);
PAINT MONO (-9135 885);
FORCEPROP 0 LASTPIN (-9125 825) $PN D71
J 2
(-9135 835);
DISPLAY 0.489362 (-9135 835);
PAINT MONO (-9135 835);
FORCEPROP 0 LASTPIN (-9125 775) $PN D73
J 2
(-9135 785);
DISPLAY 0.489362 (-9135 785);
PAINT MONO (-9135 785);
FORCEPROP 0 LASTPIN (-9125 725) $PN D74
J 2
(-9135 735);
DISPLAY 0.489362 (-9135 735);
PAINT MONO (-9135 735);
FORCEPROP 0 LASTPIN (-9125 675) $PN E1
J 2
(-9135 685);
DISPLAY 0.489362 (-9135 685);
PAINT MONO (-9135 685);
FORCEPROP 0 LASTPIN (-9125 625) $PN E3
J 2
(-9135 635);
DISPLAY 0.489362 (-9135 635);
PAINT MONO (-9135 635);
FORCEPROP 0 LASTPIN (-9125 575) $PN E6
J 2
(-9135 585);
DISPLAY 0.489362 (-9135 585);
PAINT MONO (-9135 585);
FORCEPROP 0 LASTPIN (-9125 525) $PN E7
J 2
(-9135 535);
DISPLAY 0.489362 (-9135 535);
PAINT MONO (-9135 535);
FORCEPROP 0 LASTPIN (-9125 475) $PN E8
J 2
(-9135 485);
DISPLAY 0.489362 (-9135 485);
PAINT MONO (-9135 485);
FORCEPROP 0 LASTPIN (-8025 6375) $PN E10
J 0
(-8015 6385);
DISPLAY 0.489362 (-8015 6385);
PAINT MONO (-8015 6385);
FORCEPROP 0 LASTPIN (-8025 6325) $PN E13
J 0
(-8015 6335);
DISPLAY 0.489362 (-8015 6335);
PAINT MONO (-8015 6335);
FORCEPROP 0 LASTPIN (-8025 6275) $PN E14
J 0
(-8015 6285);
DISPLAY 0.489362 (-8015 6285);
PAINT MONO (-8015 6285);
FORCEPROP 0 LASTPIN (-8025 6225) $PN E15
J 0
(-8015 6235);
DISPLAY 0.489362 (-8015 6235);
PAINT MONO (-8015 6235);
FORCEPROP 0 LASTPIN (-8025 6175) $PN E17
J 0
(-8015 6185);
DISPLAY 0.489362 (-8015 6185);
PAINT MONO (-8015 6185);
FORCEPROP 0 LASTPIN (-8025 6125) $PN E18
J 0
(-8015 6135);
DISPLAY 0.489362 (-8015 6135);
PAINT MONO (-8015 6135);
FORCEPROP 0 LASTPIN (-8025 6075) $PN E20
J 0
(-8015 6085);
DISPLAY 0.489362 (-8015 6085);
PAINT MONO (-8015 6085);
FORCEPROP 0 LASTPIN (-8025 6025) $PN E21
J 0
(-8015 6035);
DISPLAY 0.489362 (-8015 6035);
PAINT MONO (-8015 6035);
FORCEPROP 0 LASTPIN (-8025 5975) $PN E52
J 0
(-8015 5985);
DISPLAY 0.489362 (-8015 5985);
PAINT MONO (-8015 5985);
FORCEPROP 0 LASTPIN (-8025 5925) $PN E53
J 0
(-8015 5935);
DISPLAY 0.489362 (-8015 5935);
PAINT MONO (-8015 5935);
FORCEPROP 0 LASTPIN (-8025 5875) $PN E55
J 0
(-8015 5885);
DISPLAY 0.489362 (-8015 5885);
PAINT MONO (-8015 5885);
FORCEPROP 0 LASTPIN (-8025 5825) $PN E56
J 0
(-8015 5835);
DISPLAY 0.489362 (-8015 5835);
PAINT MONO (-8015 5835);
FORCEPROP 0 LASTPIN (-8025 5775) $PN E58
J 0
(-8015 5785);
DISPLAY 0.489362 (-8015 5785);
PAINT MONO (-8015 5785);
FORCEPROP 0 LASTPIN (-8025 5725) $PN E59
J 0
(-8015 5735);
DISPLAY 0.489362 (-8015 5735);
PAINT MONO (-8015 5735);
FORCEPROP 0 LASTPIN (-8025 5675) $PN E61
J 0
(-8015 5685);
DISPLAY 0.489362 (-8015 5685);
PAINT MONO (-8015 5685);
FORCEPROP 0 LASTPIN (-8025 5625) $PN E62
J 0
(-8015 5635);
DISPLAY 0.489362 (-8015 5635);
PAINT MONO (-8015 5635);
FORCEPROP 0 LASTPIN (-8025 5575) $PN E63
J 0
(-8015 5585);
DISPLAY 0.489362 (-8015 5585);
PAINT MONO (-8015 5585);
FORCEPROP 0 LASTPIN (-8025 5525) $PN E65
J 0
(-8015 5535);
DISPLAY 0.489362 (-8015 5535);
PAINT MONO (-8015 5535);
FORCEPROP 0 LASTPIN (-8025 5475) $PN E66
J 0
(-8015 5485);
DISPLAY 0.489362 (-8015 5485);
PAINT MONO (-8015 5485);
FORCEPROP 0 LASTPIN (-8025 5425) $PN E68
J 0
(-8015 5435);
DISPLAY 0.489362 (-8015 5435);
PAINT MONO (-8015 5435);
FORCEPROP 0 LASTPIN (-8025 5375) $PN E69
J 0
(-8015 5385);
DISPLAY 0.489362 (-8015 5385);
PAINT MONO (-8015 5385);
FORCEPROP 0 LASTPIN (-8025 5325) $PN E70
J 0
(-8015 5335);
DISPLAY 0.489362 (-8015 5335);
PAINT MONO (-8015 5335);
FORCEPROP 0 LASTPIN (-8025 5275) $PN E72
J 0
(-8015 5285);
DISPLAY 0.489362 (-8015 5285);
PAINT MONO (-8015 5285);
FORCEPROP 0 LASTPIN (-8025 5225) $PN E73
J 0
(-8015 5235);
DISPLAY 0.489362 (-8015 5235);
PAINT MONO (-8015 5235);
FORCEPROP 0 LASTPIN (-8025 5175) $PN E75
J 0
(-8015 5185);
DISPLAY 0.489362 (-8015 5185);
PAINT MONO (-8015 5185);
FORCEPROP 0 LASTPIN (-8025 5125) $PN F3
J 0
(-8015 5135);
DISPLAY 0.489362 (-8015 5135);
PAINT MONO (-8015 5135);
FORCEPROP 0 LASTPIN (-8025 5075) $PN F5
J 0
(-8015 5085);
DISPLAY 0.489362 (-8015 5085);
PAINT MONO (-8015 5085);
FORCEPROP 0 LASTPIN (-8025 5025) $PN F8
J 0
(-8015 5035);
DISPLAY 0.489362 (-8015 5035);
PAINT MONO (-8015 5035);
FORCEPROP 0 LASTPIN (-8025 4975) $PN F10
J 0
(-8015 4985);
DISPLAY 0.489362 (-8015 4985);
PAINT MONO (-8015 4985);
FORCEPROP 0 LASTPIN (-8025 4925) $PN F12
J 0
(-8015 4935);
DISPLAY 0.489362 (-8015 4935);
PAINT MONO (-8015 4935);
FORCEPROP 0 LASTPIN (-8025 4875) $PN F15
J 0
(-8015 4885);
DISPLAY 0.489362 (-8015 4885);
PAINT MONO (-8015 4885);
FORCEPROP 0 LASTPIN (-8025 4825) $PN F17
J 0
(-8015 4835);
DISPLAY 0.489362 (-8015 4835);
PAINT MONO (-8015 4835);
FORCEPROP 0 LASTPIN (-8025 4775) $PN F19
J 0
(-8015 4785);
DISPLAY 0.489362 (-8015 4785);
PAINT MONO (-8015 4785);
FORCEPROP 0 LASTPIN (-8025 4725) $PN F23
J 0
(-8015 4735);
DISPLAY 0.489362 (-8015 4735);
PAINT MONO (-8015 4735);
FORCEPROP 0 LASTPIN (-8025 4675) $PN F24
J 0
(-8015 4685);
DISPLAY 0.489362 (-8015 4685);
PAINT MONO (-8015 4685);
FORCEPROP 0 LASTPIN (-8025 4625) $PN F26
J 0
(-8015 4635);
DISPLAY 0.489362 (-8015 4635);
PAINT MONO (-8015 4635);
FORCEPROP 0 LASTPIN (-8025 4575) $PN F27
J 0
(-8015 4585);
DISPLAY 0.489362 (-8015 4585);
PAINT MONO (-8015 4585);
FORCEPROP 0 LASTPIN (-8025 4525) $PN F29
J 0
(-8015 4535);
DISPLAY 0.489362 (-8015 4535);
PAINT MONO (-8015 4535);
FORCEPROP 0 LASTPIN (-8025 4475) $PN F30
J 0
(-8015 4485);
DISPLAY 0.489362 (-8015 4485);
PAINT MONO (-8015 4485);
FORCEPROP 0 LASTPIN (-8025 4425) $PN F32
J 0
(-8015 4435);
DISPLAY 0.489362 (-8015 4435);
PAINT MONO (-8015 4435);
FORCEPROP 0 LASTPIN (-8025 4375) $PN F33
J 0
(-8015 4385);
DISPLAY 0.489362 (-8015 4385);
PAINT MONO (-8015 4385);
FORCEPROP 0 LASTPIN (-8025 4325) $PN F35
J 0
(-8015 4335);
DISPLAY 0.489362 (-8015 4335);
PAINT MONO (-8015 4335);
FORCEPROP 0 LASTPIN (-8025 4275) $PN F36
J 0
(-8015 4285);
DISPLAY 0.489362 (-8015 4285);
PAINT MONO (-8015 4285);
FORCEPROP 0 LASTPIN (-8025 4225) $PN F37
J 0
(-8015 4235);
DISPLAY 0.489362 (-8015 4235);
PAINT MONO (-8015 4235);
FORCEPROP 0 LASTPIN (-8025 4175) $PN F39
J 0
(-8015 4185);
DISPLAY 0.489362 (-8015 4185);
PAINT MONO (-8015 4185);
FORCEPROP 0 LASTPIN (-8025 4125) $PN F40
J 0
(-8015 4135);
DISPLAY 0.489362 (-8015 4135);
PAINT MONO (-8015 4135);
FORCEPROP 0 LASTPIN (-8025 4075) $PN F41
J 0
(-8015 4085);
DISPLAY 0.489362 (-8015 4085);
PAINT MONO (-8015 4085);
FORCEPROP 0 LASTPIN (-8025 4025) $PN F43
J 0
(-8015 4035);
DISPLAY 0.489362 (-8015 4035);
PAINT MONO (-8015 4035);
FORCEPROP 0 LASTPIN (-8025 3975) $PN F44
J 0
(-8015 3985);
DISPLAY 0.489362 (-8015 3985);
PAINT MONO (-8015 3985);
FORCEPROP 0 LASTPIN (-8025 3925) $PN F46
J 0
(-8015 3935);
DISPLAY 0.489362 (-8015 3935);
PAINT MONO (-8015 3935);
FORCEPROP 0 LASTPIN (-8025 3875) $PN F47
J 0
(-8015 3885);
DISPLAY 0.489362 (-8015 3885);
PAINT MONO (-8015 3885);
FORCEPROP 0 LASTPIN (-8025 3825) $PN F49
J 0
(-8015 3835);
DISPLAY 0.489362 (-8015 3835);
PAINT MONO (-8015 3835);
FORCEPROP 0 LASTPIN (-8025 3775) $PN F50
J 0
(-8015 3785);
DISPLAY 0.489362 (-8015 3785);
PAINT MONO (-8015 3785);
FORCEPROP 0 LASTPIN (-8025 3725) $PN F52
J 0
(-8015 3735);
DISPLAY 0.489362 (-8015 3735);
PAINT MONO (-8015 3735);
FORCEPROP 0 LASTPIN (-8025 3675) $PN F53
J 0
(-8015 3685);
DISPLAY 0.489362 (-8015 3685);
PAINT MONO (-8015 3685);
FORCEPROP 0 LASTPIN (-8025 3625) $PN F57
J 0
(-8015 3635);
DISPLAY 0.489362 (-8015 3635);
PAINT MONO (-8015 3635);
FORCEPROP 0 LASTPIN (-8025 3575) $PN F59
J 0
(-8015 3585);
DISPLAY 0.489362 (-8015 3585);
PAINT MONO (-8015 3585);
FORCEPROP 0 LASTPIN (-8025 3525) $PN F61
J 0
(-8015 3535);
DISPLAY 0.489362 (-8015 3535);
PAINT MONO (-8015 3535);
FORCEPROP 0 LASTPIN (-8025 3475) $PN F64
J 0
(-8015 3485);
DISPLAY 0.489362 (-8015 3485);
PAINT MONO (-8015 3485);
FORCEPROP 0 LASTPIN (-8025 3425) $PN F66
J 0
(-8015 3435);
DISPLAY 0.489362 (-8015 3435);
PAINT MONO (-8015 3435);
FORCEPROP 0 LASTPIN (-8025 3375) $PN F68
J 0
(-8015 3385);
DISPLAY 0.489362 (-8015 3385);
PAINT MONO (-8015 3385);
FORCEPROP 0 LASTPIN (-8025 3325) $PN F71
J 0
(-8015 3335);
DISPLAY 0.489362 (-8015 3335);
PAINT MONO (-8015 3335);
FORCEPROP 0 LASTPIN (-8025 3275) $PN F73
J 0
(-8015 3285);
DISPLAY 0.489362 (-8015 3285);
PAINT MONO (-8015 3285);
FORCEPROP 0 LASTPIN (-8025 3225) $PN G1
J 0
(-8015 3235);
DISPLAY 0.489362 (-8015 3235);
PAINT MONO (-8015 3235);
FORCEPROP 0 LASTPIN (-8025 3175) $PN G4
J 0
(-8015 3185);
DISPLAY 0.489362 (-8015 3185);
PAINT MONO (-8015 3185);
FORCEPROP 0 LASTPIN (-8025 3125) $PN G6
J 0
(-8015 3135);
DISPLAY 0.489362 (-8015 3135);
PAINT MONO (-8015 3135);
FORCEPROP 0 LASTPIN (-8025 3075) $PN G8
J 0
(-8015 3085);
DISPLAY 0.489362 (-8015 3085);
PAINT MONO (-8015 3085);
FORCEPROP 0 LASTPIN (-8025 3025) $PN G11
J 0
(-8015 3035);
DISPLAY 0.489362 (-8015 3035);
PAINT MONO (-8015 3035);
FORCEPROP 0 LASTPIN (-8025 2975) $PN G13
J 0
(-8015 2985);
DISPLAY 0.489362 (-8015 2985);
PAINT MONO (-8015 2985);
FORCEPROP 0 LASTPIN (-8025 2925) $PN G15
J 0
(-8015 2935);
DISPLAY 0.489362 (-8015 2935);
PAINT MONO (-8015 2935);
FORCEPROP 0 LASTPIN (-8025 2875) $PN G18
J 0
(-8015 2885);
DISPLAY 0.489362 (-8015 2885);
PAINT MONO (-8015 2885);
FORCEPROP 0 LASTPIN (-8025 2825) $PN G20
J 0
(-8015 2835);
DISPLAY 0.489362 (-8015 2835);
PAINT MONO (-8015 2835);
FORCEPROP 0 LASTPIN (-8025 2775) $PN G22
J 0
(-8015 2785);
DISPLAY 0.489362 (-8015 2785);
PAINT MONO (-8015 2785);
FORCEPROP 0 LASTPIN (-8025 2725) $PN G25
J 0
(-8015 2735);
DISPLAY 0.489362 (-8015 2735);
PAINT MONO (-8015 2735);
FORCEPROP 0 LASTPIN (-8025 2675) $PN G28
J 0
(-8015 2685);
DISPLAY 0.489362 (-8015 2685);
PAINT MONO (-8015 2685);
FORCEPROP 0 LASTPIN (-8025 2625) $PN G31
J 0
(-8015 2635);
DISPLAY 0.489362 (-8015 2635);
PAINT MONO (-8015 2635);
FORCEPROP 0 LASTPIN (-8025 2575) $PN G34
J 0
(-8015 2585);
DISPLAY 0.489362 (-8015 2585);
PAINT MONO (-8015 2585);
FORCEPROP 0 LASTPIN (-8025 2525) $PN G42
J 0
(-8015 2535);
DISPLAY 0.489362 (-8015 2535);
PAINT MONO (-8015 2535);
FORCEPROP 0 LASTPIN (-8025 2475) $PN G45
J 0
(-8015 2485);
DISPLAY 0.489362 (-8015 2485);
PAINT MONO (-8015 2485);
FORCEPROP 0 LASTPIN (-8025 2425) $PN G48
J 0
(-8015 2435);
DISPLAY 0.489362 (-8015 2435);
PAINT MONO (-8015 2435);
FORCEPROP 0 LASTPIN (-8025 2375) $PN G51
J 0
(-8015 2385);
DISPLAY 0.489362 (-8015 2385);
PAINT MONO (-8015 2385);
FORCEPROP 0 LASTPIN (-8025 2325) $PN G54
J 0
(-8015 2335);
DISPLAY 0.489362 (-8015 2335);
PAINT MONO (-8015 2335);
FORCEPROP 0 LASTPIN (-8025 2275) $PN G56
J 0
(-8015 2285);
DISPLAY 0.489362 (-8015 2285);
PAINT MONO (-8015 2285);
FORCEPROP 0 LASTPIN (-8025 2225) $PN G58
J 0
(-8015 2235);
DISPLAY 0.489362 (-8015 2235);
PAINT MONO (-8015 2235);
FORCEPROP 0 LASTPIN (-8025 2175) $PN G61
J 0
(-8015 2185);
DISPLAY 0.489362 (-8015 2185);
PAINT MONO (-8015 2185);
FORCEPROP 0 LASTPIN (-8025 2125) $PN G63
J 0
(-8015 2135);
DISPLAY 0.489362 (-8015 2135);
PAINT MONO (-8015 2135);
FORCEPROP 0 LASTPIN (-8025 2075) $PN G65
J 0
(-8015 2085);
DISPLAY 0.489362 (-8015 2085);
PAINT MONO (-8015 2085);
FORCEPROP 0 LASTPIN (-8025 2025) $PN G68
J 0
(-8015 2035);
DISPLAY 0.489362 (-8015 2035);
PAINT MONO (-8015 2035);
FORCEPROP 0 LASTPIN (-8025 1975) $PN G70
J 0
(-8015 1985);
DISPLAY 0.489362 (-8015 1985);
PAINT MONO (-8015 1985);
FORCEPROP 0 LASTPIN (-8025 1925) $PN G72
J 0
(-8015 1935);
DISPLAY 0.489362 (-8015 1935);
PAINT MONO (-8015 1935);
FORCEPROP 0 LASTPIN (-8025 1875) $PN G75
J 0
(-8015 1885);
DISPLAY 0.489362 (-8015 1885);
PAINT MONO (-8015 1885);
FORCEPROP 0 LASTPIN (-8025 1825) $PN H3
J 0
(-8015 1835);
DISPLAY 0.489362 (-8015 1835);
PAINT MONO (-8015 1835);
FORCEPROP 0 LASTPIN (-8025 1775) $PN H8
J 0
(-8015 1785);
DISPLAY 0.489362 (-8015 1785);
PAINT MONO (-8015 1785);
FORCEPROP 0 LASTPIN (-8025 1725) $PN H10
J 0
(-8015 1735);
DISPLAY 0.489362 (-8015 1735);
PAINT MONO (-8015 1735);
FORCEPROP 0 LASTPIN (-8025 1675) $PN H15
J 0
(-8015 1685);
DISPLAY 0.489362 (-8015 1685);
PAINT MONO (-8015 1685);
FORCEPROP 0 LASTPIN (-8025 1625) $PN H17
J 0
(-8015 1635);
DISPLAY 0.489362 (-8015 1635);
PAINT MONO (-8015 1635);
FORCEPROP 0 LASTPIN (-8025 1575) $PN H22
J 0
(-8015 1585);
DISPLAY 0.489362 (-8015 1585);
PAINT MONO (-8015 1585);
FORCEPROP 0 LASTPIN (-8025 1525) $PN H25
J 0
(-8015 1535);
DISPLAY 0.489362 (-8015 1535);
PAINT MONO (-8015 1535);
FORCEPROP 0 LASTPIN (-8025 1475) $PN H28
J 0
(-8015 1485);
DISPLAY 0.489362 (-8015 1485);
PAINT MONO (-8015 1485);
FORCEPROP 0 LASTPIN (-8025 1425) $PN H31
J 0
(-8015 1435);
DISPLAY 0.489362 (-8015 1435);
PAINT MONO (-8015 1435);
FORCEPROP 0 LASTPIN (-8025 1375) $PN H34
J 0
(-8015 1385);
DISPLAY 0.489362 (-8015 1385);
PAINT MONO (-8015 1385);
FORCEPROP 0 LASTPIN (-8025 1325) $PN H37
J 0
(-8015 1335);
DISPLAY 0.489362 (-8015 1335);
PAINT MONO (-8015 1335);
FORCEPROP 0 LASTPIN (-8025 1275) $PN H39
J 0
(-8015 1285);
DISPLAY 0.489362 (-8015 1285);
PAINT MONO (-8015 1285);
FORCEPROP 0 LASTPIN (-8025 1225) $PN H42
J 0
(-8015 1235);
DISPLAY 0.489362 (-8015 1235);
PAINT MONO (-8015 1235);
FORCEPROP 0 LASTPIN (-8025 1175) $PN H45
J 0
(-8015 1185);
DISPLAY 0.489362 (-8015 1185);
PAINT MONO (-8015 1185);
FORCEPROP 0 LASTPIN (-8025 1125) $PN H48
J 0
(-8015 1135);
DISPLAY 0.489362 (-8015 1135);
PAINT MONO (-8015 1135);
FORCEPROP 0 LASTPIN (-8025 1075) $PN H51
J 0
(-8015 1085);
DISPLAY 0.489362 (-8015 1085);
PAINT MONO (-8015 1085);
FORCEPROP 0 LASTPIN (-8025 1025) $PN H54
J 0
(-8015 1035);
DISPLAY 0.489362 (-8015 1035);
PAINT MONO (-8015 1035);
FORCEPROP 0 LASTPIN (-8025 975) $PN H59
J 0
(-8015 985);
DISPLAY 0.489362 (-8015 985);
PAINT MONO (-8015 985);
FORCEPROP 0 LASTPIN (-8025 925) $PN H61
J 0
(-8015 935);
DISPLAY 0.489362 (-8015 935);
PAINT MONO (-8015 935);
FORCEPROP 0 LASTPIN (-8025 875) $PN H66
J 0
(-8015 885);
DISPLAY 0.489362 (-8015 885);
PAINT MONO (-8015 885);
FORCEPROP 0 LASTPIN (-8025 825) $PN H68
J 0
(-8015 835);
DISPLAY 0.489362 (-8015 835);
PAINT MONO (-8015 835);
FORCEPROP 0 LASTPIN (-8025 775) $PN H73
J 0
(-8015 785);
DISPLAY 0.489362 (-8015 785);
PAINT MONO (-8015 785);
FORCEPROP 0 LASTPIN (-8025 725) $PN J1
J 0
(-8015 735);
DISPLAY 0.489362 (-8015 735);
PAINT MONO (-8015 735);
FORCEPROP 0 LASTPIN (-8025 675) $PN J4
J 0
(-8015 685);
DISPLAY 0.489362 (-8015 685);
PAINT MONO (-8015 685);
FORCEPROP 0 LASTPIN (-8025 625) $PN J6
J 0
(-8015 635);
DISPLAY 0.489362 (-8015 635);
PAINT MONO (-8015 635);
FORCEPROP 0 LASTPIN (-8025 575) $PN J8
J 0
(-8015 585);
DISPLAY 0.489362 (-8015 585);
PAINT MONO (-8015 585);
FORCEPROP 0 LASTPIN (-8025 525) $PN J11
J 0
(-8015 535);
DISPLAY 0.489362 (-8015 535);
PAINT MONO (-8015 535);
FORCEPROP 0 LASTPIN (-8025 475) $PN J13
J 0
(-8015 485);
DISPLAY 0.489362 (-8015 485);
PAINT MONO (-8015 485);
FORCEPROP 2 LAST PART_TYPE SMLF
J 0
(-8975 6700);
DISPLAY 1.021277 (-8975 6700);
FORCEPROP 1 LAST MATERIAL IO
J 0
(-8970 6507);
DISPLAY 0.489362 (-8970 6507);
PAINT SKYBLUE (-8970 6507);
FORCEPROP 2 LAST VALUE SOCKET6096_13568-001
J 0
(-8975 6575);
DISPLAY 0.489362 (-8975 6575);
PAINT SKYBLUE (-8975 6575);
FORCEPROP 2 LAST CDS_LIB pure_quanta
J 0
(-8575 3425);
DISPLAY INVISIBLE (-8575 3425);
FORCEPROP 1 LAST CDS_LMAN_SYM_OUTLINE -400,3050,400,-3050
J 0
(-8575 3425);
DISPLAY 0.468085 (-8575 3425);
PAINT GREEN (-8575 3425);
DISPLAY INVISIBLE (-8575 3425);
FORCEPROP 1 LAST NEEDS_NO_SIZE TRUE
J 0
(-8575 3425);
DISPLAY 0.723404 (-8575 3425);
PAINT GREEN (-8575 3425);
DISPLAY INVISIBLE (-8575 3425);
FORCEPROP 1 LAST PATH I1
J 0
(-8575 3425);
DISPLAY 0.723404 (-8575 3425);
PAINT GREEN (-8575 3425);
DISPLAY INVISIBLE (-8575 3425);
FORCEPROP 1 LAST PART_NUMBER DGA^6000030
J 0
(-8975 6650);
DISPLAY 0.489362 (-8975 6650);
PAINT SKYBLUE (-8975 6650);
DISPLAY INVISIBLE (-8975 6650);
FORCEADD GENOA_SP5..30
(-5575 3475);
FORCEPROP 1 LAST LOCATION U26
J 0
(-5975 6650);
DISPLAY 0.489362 (-5975 6650);
PAINT SKYBLUE (-5975 6650);
FORCEPROP 0 LAST $SEC 30
J 0
(-5950 6875);
DISPLAY 0.680851 (-5950 6875);
PAINT MONO (-5950 6875);
DISPLAY INVISIBLE (-5950 6875);
FORCEPROP 0 LAST CDS_SEC 30
J 0
(-5950 6875);
DISPLAY 1.021277 (-5950 6875);
DISPLAY INVISIBLE (-5950 6875);
FORCEPROP 0 LASTPIN (-5025 5625) $PN AA1
J 0
(-5015 5635);
DISPLAY 0.489362 (-5015 5635);
PAINT MONO (-5015 5635);
FORCEPROP 0 LASTPIN (-5025 5575) $PN AA4
J 0
(-5015 5585);
DISPLAY 0.489362 (-5015 5585);
PAINT MONO (-5015 5585);
FORCEPROP 0 LASTPIN (-5025 5525) $PN AA6
J 0
(-5015 5535);
DISPLAY 0.489362 (-5015 5535);
PAINT MONO (-5015 5535);
FORCEPROP 0 LASTPIN (-5025 5475) $PN AA8
J 0
(-5015 5485);
DISPLAY 0.489362 (-5015 5485);
PAINT MONO (-5015 5485);
FORCEPROP 0 LASTPIN (-5025 5425) $PN AA11
J 0
(-5015 5435);
DISPLAY 0.489362 (-5015 5435);
PAINT MONO (-5015 5435);
FORCEPROP 0 LASTPIN (-5025 5375) $PN AA13
J 0
(-5015 5385);
DISPLAY 0.489362 (-5015 5385);
PAINT MONO (-5015 5385);
FORCEPROP 0 LASTPIN (-5025 5325) $PN AA15
J 0
(-5015 5335);
DISPLAY 0.489362 (-5015 5335);
PAINT MONO (-5015 5335);
FORCEPROP 0 LASTPIN (-5025 5275) $PN AA18
J 0
(-5015 5285);
DISPLAY 0.489362 (-5015 5285);
PAINT MONO (-5015 5285);
FORCEPROP 0 LASTPIN (-5025 5225) $PN AA20
J 0
(-5015 5235);
DISPLAY 0.489362 (-5015 5235);
PAINT MONO (-5015 5235);
FORCEPROP 0 LASTPIN (-5025 5175) $PN AA31
J 0
(-5015 5185);
DISPLAY 0.489362 (-5015 5185);
PAINT MONO (-5015 5185);
FORCEPROP 0 LASTPIN (-5025 5125) $PN AA34
J 0
(-5015 5135);
DISPLAY 0.489362 (-5015 5135);
PAINT MONO (-5015 5135);
FORCEPROP 0 LASTPIN (-5025 5075) $PN AA35
J 0
(-5015 5085);
DISPLAY 0.489362 (-5015 5085);
PAINT MONO (-5015 5085);
FORCEPROP 0 LASTPIN (-5025 5025) $PN AA36
J 0
(-5015 5035);
DISPLAY 0.489362 (-5015 5035);
PAINT MONO (-5015 5035);
FORCEPROP 0 LASTPIN (-5025 4975) $PN AA40
J 0
(-5015 4985);
DISPLAY 0.489362 (-5015 4985);
PAINT MONO (-5015 4985);
FORCEPROP 0 LASTPIN (-5025 4925) $PN AA41
J 0
(-5015 4935);
DISPLAY 0.489362 (-5015 4935);
PAINT MONO (-5015 4935);
FORCEPROP 0 LASTPIN (-5025 4875) $PN AA45
J 0
(-5015 4885);
DISPLAY 0.489362 (-5015 4885);
PAINT MONO (-5015 4885);
FORCEPROP 0 LASTPIN (-5025 4825) $PN AA56
J 0
(-5015 4835);
DISPLAY 0.489362 (-5015 4835);
PAINT MONO (-5015 4835);
FORCEPROP 0 LASTPIN (-5025 4775) $PN AA58
J 0
(-5015 4785);
DISPLAY 0.489362 (-5015 4785);
PAINT MONO (-5015 4785);
FORCEPROP 0 LASTPIN (-5025 4725) $PN AA61
J 0
(-5015 4735);
DISPLAY 0.489362 (-5015 4735);
PAINT MONO (-5015 4735);
FORCEPROP 0 LASTPIN (-5025 4675) $PN AA63
J 0
(-5015 4685);
DISPLAY 0.489362 (-5015 4685);
PAINT MONO (-5015 4685);
FORCEPROP 0 LASTPIN (-5025 4625) $PN AA65
J 0
(-5015 4635);
DISPLAY 0.489362 (-5015 4635);
PAINT MONO (-5015 4635);
FORCEPROP 0 LASTPIN (-5025 4575) $PN AA68
J 0
(-5015 4585);
DISPLAY 0.489362 (-5015 4585);
PAINT MONO (-5015 4585);
FORCEPROP 0 LASTPIN (-5025 4525) $PN AA70
J 0
(-5015 4535);
DISPLAY 0.489362 (-5015 4535);
PAINT MONO (-5015 4535);
FORCEPROP 0 LASTPIN (-5025 4475) $PN AA75
J 0
(-5015 4485);
DISPLAY 0.489362 (-5015 4485);
PAINT MONO (-5015 4485);
FORCEPROP 0 LASTPIN (-5025 4425) $PN AB3
J 0
(-5015 4435);
DISPLAY 0.489362 (-5015 4435);
PAINT MONO (-5015 4435);
FORCEPROP 0 LASTPIN (-5025 4375) $PN AB5
J 0
(-5015 4385);
DISPLAY 0.489362 (-5015 4385);
PAINT MONO (-5015 4385);
FORCEPROP 0 LASTPIN (-5025 4325) $PN AB8
J 0
(-5015 4335);
DISPLAY 0.489362 (-5015 4335);
PAINT MONO (-5015 4335);
FORCEPROP 0 LASTPIN (-5025 4275) $PN AB10
J 0
(-5015 4285);
DISPLAY 0.489362 (-5015 4285);
PAINT MONO (-5015 4285);
FORCEPROP 0 LASTPIN (-5025 4225) $PN AB12
J 0
(-5015 4235);
DISPLAY 0.489362 (-5015 4235);
PAINT MONO (-5015 4235);
FORCEPROP 0 LASTPIN (-5025 4175) $PN AB15
J 0
(-5015 4185);
DISPLAY 0.489362 (-5015 4185);
PAINT MONO (-5015 4185);
FORCEPROP 0 LASTPIN (-5025 4125) $PN AB17
J 0
(-5015 4135);
DISPLAY 0.489362 (-5015 4135);
PAINT MONO (-5015 4135);
FORCEPROP 0 LASTPIN (-5025 4075) $PN AB19
J 0
(-5015 4085);
DISPLAY 0.489362 (-5015 4085);
PAINT MONO (-5015 4085);
FORCEPROP 0 LASTPIN (-5025 4025) $PN AB22
J 0
(-5015 4035);
DISPLAY 0.489362 (-5015 4035);
PAINT MONO (-5015 4035);
FORCEPROP 0 LASTPIN (-5025 3975) $PN AB25
J 0
(-5015 3985);
DISPLAY 0.489362 (-5015 3985);
PAINT MONO (-5015 3985);
FORCEPROP 0 LASTPIN (-5025 3925) $PN AB28
J 0
(-5015 3935);
DISPLAY 0.489362 (-5015 3935);
PAINT MONO (-5015 3935);
FORCEPROP 0 LASTPIN (-5025 3875) $PN AB31
J 0
(-5015 3885);
DISPLAY 0.489362 (-5015 3885);
PAINT MONO (-5015 3885);
FORCEPROP 0 LASTPIN (-5025 3825) $PN AB34
J 0
(-5015 3835);
DISPLAY 0.489362 (-5015 3835);
PAINT MONO (-5015 3835);
FORCEPROP 0 LASTPIN (-5025 3775) $PN AB37
J 0
(-5015 3785);
DISPLAY 0.489362 (-5015 3785);
PAINT MONO (-5015 3785);
FORCEPROP 0 LASTPIN (-5025 3725) $PN AB39
J 0
(-5015 3735);
DISPLAY 0.489362 (-5015 3735);
PAINT MONO (-5015 3735);
FORCEPROP 0 LASTPIN (-5025 3675) $PN AB42
J 0
(-5015 3685);
DISPLAY 0.489362 (-5015 3685);
PAINT MONO (-5015 3685);
FORCEPROP 0 LASTPIN (-5025 3625) $PN AB45
J 0
(-5015 3635);
DISPLAY 0.489362 (-5015 3635);
PAINT MONO (-5015 3635);
FORCEPROP 0 LASTPIN (-5025 3575) $PN AB48
J 0
(-5015 3585);
DISPLAY 0.489362 (-5015 3585);
PAINT MONO (-5015 3585);
FORCEPROP 0 LASTPIN (-5025 3525) $PN AB51
J 0
(-5015 3535);
DISPLAY 0.489362 (-5015 3535);
PAINT MONO (-5015 3535);
FORCEPROP 0 LASTPIN (-5025 3475) $PN AB54
J 0
(-5015 3485);
DISPLAY 0.489362 (-5015 3485);
PAINT MONO (-5015 3485);
FORCEPROP 0 LASTPIN (-5025 3425) $PN AB57
J 0
(-5015 3435);
DISPLAY 0.489362 (-5015 3435);
PAINT MONO (-5015 3435);
FORCEPROP 0 LASTPIN (-5025 3375) $PN AB59
J 0
(-5015 3385);
DISPLAY 0.489362 (-5015 3385);
PAINT MONO (-5015 3385);
FORCEPROP 0 LASTPIN (-5025 3325) $PN AB61
J 0
(-5015 3335);
DISPLAY 0.489362 (-5015 3335);
PAINT MONO (-5015 3335);
FORCEPROP 0 LASTPIN (-5025 3275) $PN AB64
J 0
(-5015 3285);
DISPLAY 0.489362 (-5015 3285);
PAINT MONO (-5015 3285);
FORCEPROP 0 LASTPIN (-5025 3225) $PN AB66
J 0
(-5015 3235);
DISPLAY 0.489362 (-5015 3235);
PAINT MONO (-5015 3235);
FORCEPROP 0 LASTPIN (-5025 3175) $PN AB68
J 0
(-5015 3185);
DISPLAY 0.489362 (-5015 3185);
PAINT MONO (-5015 3185);
FORCEPROP 0 LASTPIN (-5025 3125) $PN AB71
J 0
(-5015 3135);
DISPLAY 0.489362 (-5015 3135);
PAINT MONO (-5015 3135);
FORCEPROP 0 LASTPIN (-5025 3075) $PN AB73
J 0
(-5015 3085);
DISPLAY 0.489362 (-5015 3085);
PAINT MONO (-5015 3085);
FORCEPROP 0 LASTPIN (-5025 3025) $PN AC1
J 0
(-5015 3035);
DISPLAY 0.489362 (-5015 3035);
PAINT MONO (-5015 3035);
FORCEPROP 0 LASTPIN (-5025 2975) $PN AC6
J 0
(-5015 2985);
DISPLAY 0.489362 (-5015 2985);
PAINT MONO (-5015 2985);
FORCEPROP 0 LASTPIN (-5025 2925) $PN AC8
J 0
(-5015 2935);
DISPLAY 0.489362 (-5015 2935);
PAINT MONO (-5015 2935);
FORCEPROP 0 LASTPIN (-5025 2875) $PN AC13
J 0
(-5015 2885);
DISPLAY 0.489362 (-5015 2885);
PAINT MONO (-5015 2885);
FORCEPROP 0 LASTPIN (-5025 2825) $PN AC15
J 0
(-5015 2835);
DISPLAY 0.489362 (-5015 2835);
PAINT MONO (-5015 2835);
FORCEPROP 0 LASTPIN (-5025 2775) $PN AC20
J 0
(-5015 2785);
DISPLAY 0.489362 (-5015 2785);
PAINT MONO (-5015 2785);
FORCEPROP 0 LASTPIN (-5025 2725) $PN AC22
J 0
(-5015 2735);
DISPLAY 0.489362 (-5015 2735);
PAINT MONO (-5015 2735);
FORCEPROP 0 LASTPIN (-5025 2675) $PN AC25
J 0
(-5015 2685);
DISPLAY 0.489362 (-5015 2685);
PAINT MONO (-5015 2685);
FORCEPROP 0 LASTPIN (-5025 2625) $PN AC28
J 0
(-5015 2635);
DISPLAY 0.489362 (-5015 2635);
PAINT MONO (-5015 2635);
FORCEPROP 0 LASTPIN (-5025 2575) $PN AC31
J 0
(-5015 2585);
DISPLAY 0.489362 (-5015 2585);
PAINT MONO (-5015 2585);
FORCEPROP 0 LASTPIN (-5025 2525) $PN AC34
J 0
(-5015 2535);
DISPLAY 0.489362 (-5015 2535);
PAINT MONO (-5015 2535);
FORCEPROP 0 LASTPIN (-5025 2475) $PN AC42
J 0
(-5015 2485);
DISPLAY 0.489362 (-5015 2485);
PAINT MONO (-5015 2485);
FORCEPROP 0 LASTPIN (-5025 2425) $PN AC45
J 0
(-5015 2435);
DISPLAY 0.489362 (-5015 2435);
PAINT MONO (-5015 2435);
FORCEPROP 0 LASTPIN (-5025 2375) $PN AC48
J 0
(-5015 2385);
DISPLAY 0.489362 (-5015 2385);
PAINT MONO (-5015 2385);
FORCEPROP 0 LASTPIN (-5025 2325) $PN AC51
J 0
(-5015 2335);
DISPLAY 0.489362 (-5015 2335);
PAINT MONO (-5015 2335);
FORCEPROP 0 LASTPIN (-5025 2275) $PN AC54
J 0
(-5015 2285);
DISPLAY 0.489362 (-5015 2285);
PAINT MONO (-5015 2285);
FORCEPROP 0 LASTPIN (-5025 2225) $PN AC56
J 0
(-5015 2235);
DISPLAY 0.489362 (-5015 2235);
PAINT MONO (-5015 2235);
FORCEPROP 0 LASTPIN (-5025 2175) $PN AC61
J 0
(-5015 2185);
DISPLAY 0.489362 (-5015 2185);
PAINT MONO (-5015 2185);
FORCEPROP 0 LASTPIN (-5025 2125) $PN AC63
J 0
(-5015 2135);
DISPLAY 0.489362 (-5015 2135);
PAINT MONO (-5015 2135);
FORCEPROP 0 LASTPIN (-5025 2075) $PN AC68
J 0
(-5015 2085);
DISPLAY 0.489362 (-5015 2085);
PAINT MONO (-5015 2085);
FORCEPROP 0 LASTPIN (-5025 2025) $PN AC70
J 0
(-5015 2035);
DISPLAY 0.489362 (-5015 2035);
PAINT MONO (-5015 2035);
FORCEPROP 0 LASTPIN (-5025 1975) $PN AC75
J 0
(-5015 1985);
DISPLAY 0.489362 (-5015 1985);
PAINT MONO (-5015 1985);
FORCEPROP 0 LASTPIN (-5025 1925) $PN AD3
J 0
(-5015 1935);
DISPLAY 0.489362 (-5015 1935);
PAINT MONO (-5015 1935);
FORCEPROP 0 LASTPIN (-5025 1875) $PN AD5
J 0
(-5015 1885);
DISPLAY 0.489362 (-5015 1885);
PAINT MONO (-5015 1885);
FORCEPROP 0 LASTPIN (-5025 1825) $PN AD8
J 0
(-5015 1835);
DISPLAY 0.489362 (-5015 1835);
PAINT MONO (-5015 1835);
FORCEPROP 0 LASTPIN (-5025 1775) $PN AD10
J 0
(-5015 1785);
DISPLAY 0.489362 (-5015 1785);
PAINT MONO (-5015 1785);
FORCEPROP 0 LASTPIN (-5025 1725) $PN AD12
J 0
(-5015 1735);
DISPLAY 0.489362 (-5015 1735);
PAINT MONO (-5015 1735);
FORCEPROP 0 LASTPIN (-5025 1675) $PN AD15
J 0
(-5015 1685);
DISPLAY 0.489362 (-5015 1685);
PAINT MONO (-5015 1685);
FORCEPROP 0 LASTPIN (-5025 1625) $PN AD17
J 0
(-5015 1635);
DISPLAY 0.489362 (-5015 1635);
PAINT MONO (-5015 1635);
FORCEPROP 0 LASTPIN (-5025 1575) $PN AD19
J 0
(-5015 1585);
DISPLAY 0.489362 (-5015 1585);
PAINT MONO (-5015 1585);
FORCEPROP 0 LASTPIN (-5025 1525) $PN AD23
J 0
(-5015 1535);
DISPLAY 0.489362 (-5015 1535);
PAINT MONO (-5015 1535);
FORCEPROP 0 LASTPIN (-5025 1475) $PN AD24
J 0
(-5015 1485);
DISPLAY 0.489362 (-5015 1485);
PAINT MONO (-5015 1485);
FORCEPROP 0 LASTPIN (-5025 1425) $PN AD25
J 0
(-5015 1435);
DISPLAY 0.489362 (-5015 1435);
PAINT MONO (-5015 1435);
FORCEPROP 0 LASTPIN (-5025 1375) $PN AD26
J 0
(-5015 1385);
DISPLAY 0.489362 (-5015 1385);
PAINT MONO (-5015 1385);
FORCEPROP 0 LASTPIN (-5025 1325) $PN AD27
J 0
(-5015 1335);
DISPLAY 0.489362 (-5015 1335);
PAINT MONO (-5015 1335);
FORCEPROP 0 LASTPIN (-5025 1275) $PN AD28
J 0
(-5015 1285);
DISPLAY 0.489362 (-5015 1285);
PAINT MONO (-5015 1285);
FORCEPROP 0 LASTPIN (-5025 1225) $PN AD29
J 0
(-5015 1235);
DISPLAY 0.489362 (-5015 1235);
PAINT MONO (-5015 1235);
FORCEPROP 0 LASTPIN (-5025 1175) $PN AD30
J 0
(-5015 1185);
DISPLAY 0.489362 (-5015 1185);
PAINT MONO (-5015 1185);
FORCEPROP 0 LASTPIN (-5025 1125) $PN AD32
J 0
(-5015 1135);
DISPLAY 0.489362 (-5015 1135);
PAINT MONO (-5015 1135);
FORCEPROP 0 LASTPIN (-5025 1075) $PN AD33
J 0
(-5015 1085);
DISPLAY 0.489362 (-5015 1085);
PAINT MONO (-5015 1085);
FORCEPROP 0 LASTPIN (-5025 1025) $PN AD34
J 0
(-5015 1035);
DISPLAY 0.489362 (-5015 1035);
PAINT MONO (-5015 1035);
FORCEPROP 0 LASTPIN (-5025 975) $PN AD37
J 0
(-5015 985);
DISPLAY 0.489362 (-5015 985);
PAINT MONO (-5015 985);
FORCEPROP 0 LASTPIN (-5025 925) $PN AD39
J 0
(-5015 935);
DISPLAY 0.489362 (-5015 935);
PAINT MONO (-5015 935);
FORCEPROP 0 LASTPIN (-5025 875) $PN AD42
J 0
(-5015 885);
DISPLAY 0.489362 (-5015 885);
PAINT MONO (-5015 885);
FORCEPROP 0 LASTPIN (-5025 825) $PN AD43
J 0
(-5015 835);
DISPLAY 0.489362 (-5015 835);
PAINT MONO (-5015 835);
FORCEPROP 0 LASTPIN (-5025 775) $PN AD44
J 0
(-5015 785);
DISPLAY 0.489362 (-5015 785);
PAINT MONO (-5015 785);
FORCEPROP 0 LASTPIN (-5025 725) $PN AD45
J 0
(-5015 735);
DISPLAY 0.489362 (-5015 735);
PAINT MONO (-5015 735);
FORCEPROP 0 LASTPIN (-5025 675) $PN AD46
J 0
(-5015 685);
DISPLAY 0.489362 (-5015 685);
PAINT MONO (-5015 685);
FORCEPROP 0 LASTPIN (-5025 625) $PN AD47
J 0
(-5015 635);
DISPLAY 0.489362 (-5015 635);
PAINT MONO (-5015 635);
FORCEPROP 0 LASTPIN (-5025 575) $PN AD48
J 0
(-5015 585);
DISPLAY 0.489362 (-5015 585);
PAINT MONO (-5015 585);
FORCEPROP 0 LASTPIN (-6125 6325) $PN T66
J 2
(-6135 6335);
DISPLAY 0.489362 (-6135 6335);
PAINT MONO (-6135 6335);
FORCEPROP 0 LASTPIN (-6125 6275) $PN T68
J 2
(-6135 6285);
DISPLAY 0.489362 (-6135 6285);
PAINT MONO (-6135 6285);
FORCEPROP 0 LASTPIN (-6125 6225) $PN T71
J 2
(-6135 6235);
DISPLAY 0.489362 (-6135 6235);
PAINT MONO (-6135 6235);
FORCEPROP 0 LASTPIN (-6125 6175) $PN T73
J 2
(-6135 6185);
DISPLAY 0.489362 (-6135 6185);
PAINT MONO (-6135 6185);
FORCEPROP 0 LASTPIN (-6125 6125) $PN U1
J 2
(-6135 6135);
DISPLAY 0.489362 (-6135 6135);
PAINT MONO (-6135 6135);
FORCEPROP 0 LASTPIN (-6125 6075) $PN U6
J 2
(-6135 6085);
DISPLAY 0.489362 (-6135 6085);
PAINT MONO (-6135 6085);
FORCEPROP 0 LASTPIN (-6125 6025) $PN U8
J 2
(-6135 6035);
DISPLAY 0.489362 (-6135 6035);
PAINT MONO (-6135 6035);
FORCEPROP 0 LASTPIN (-6125 5975) $PN U13
J 2
(-6135 5985);
DISPLAY 0.489362 (-6135 5985);
PAINT MONO (-6135 5985);
FORCEPROP 0 LASTPIN (-6125 5925) $PN U15
J 2
(-6135 5935);
DISPLAY 0.489362 (-6135 5935);
PAINT MONO (-6135 5935);
FORCEPROP 0 LASTPIN (-6125 5875) $PN U20
J 2
(-6135 5885);
DISPLAY 0.489362 (-6135 5885);
PAINT MONO (-6135 5885);
FORCEPROP 0 LASTPIN (-6125 5825) $PN U22
J 2
(-6135 5835);
DISPLAY 0.489362 (-6135 5835);
PAINT MONO (-6135 5835);
FORCEPROP 0 LASTPIN (-6125 5775) $PN U25
J 2
(-6135 5785);
DISPLAY 0.489362 (-6135 5785);
PAINT MONO (-6135 5785);
FORCEPROP 0 LASTPIN (-6125 5725) $PN U28
J 2
(-6135 5735);
DISPLAY 0.489362 (-6135 5735);
PAINT MONO (-6135 5735);
FORCEPROP 0 LASTPIN (-6125 5675) $PN U31
J 2
(-6135 5685);
DISPLAY 0.489362 (-6135 5685);
PAINT MONO (-6135 5685);
FORCEPROP 0 LASTPIN (-6125 5625) $PN U34
J 2
(-6135 5635);
DISPLAY 0.489362 (-6135 5635);
PAINT MONO (-6135 5635);
FORCEPROP 0 LASTPIN (-6125 5575) $PN U42
J 2
(-6135 5585);
DISPLAY 0.489362 (-6135 5585);
PAINT MONO (-6135 5585);
FORCEPROP 0 LASTPIN (-6125 5525) $PN U45
J 2
(-6135 5535);
DISPLAY 0.489362 (-6135 5535);
PAINT MONO (-6135 5535);
FORCEPROP 0 LASTPIN (-6125 5475) $PN U48
J 2
(-6135 5485);
DISPLAY 0.489362 (-6135 5485);
PAINT MONO (-6135 5485);
FORCEPROP 0 LASTPIN (-6125 5425) $PN U51
J 2
(-6135 5435);
DISPLAY 0.489362 (-6135 5435);
PAINT MONO (-6135 5435);
FORCEPROP 0 LASTPIN (-6125 5375) $PN U54
J 2
(-6135 5385);
DISPLAY 0.489362 (-6135 5385);
PAINT MONO (-6135 5385);
FORCEPROP 0 LASTPIN (-6125 5325) $PN U56
J 2
(-6135 5335);
DISPLAY 0.489362 (-6135 5335);
PAINT MONO (-6135 5335);
FORCEPROP 0 LASTPIN (-6125 5275) $PN U61
J 2
(-6135 5285);
DISPLAY 0.489362 (-6135 5285);
PAINT MONO (-6135 5285);
FORCEPROP 0 LASTPIN (-6125 5225) $PN U63
J 2
(-6135 5235);
DISPLAY 0.489362 (-6135 5235);
PAINT MONO (-6135 5235);
FORCEPROP 0 LASTPIN (-6125 5175) $PN U68
J 2
(-6135 5185);
DISPLAY 0.489362 (-6135 5185);
PAINT MONO (-6135 5185);
FORCEPROP 0 LASTPIN (-6125 5125) $PN U70
J 2
(-6135 5135);
DISPLAY 0.489362 (-6135 5135);
PAINT MONO (-6135 5135);
FORCEPROP 0 LASTPIN (-6125 5075) $PN U75
J 2
(-6135 5085);
DISPLAY 0.489362 (-6135 5085);
PAINT MONO (-6135 5085);
FORCEPROP 0 LASTPIN (-6125 5025) $PN V3
J 2
(-6135 5035);
DISPLAY 0.489362 (-6135 5035);
PAINT MONO (-6135 5035);
FORCEPROP 0 LASTPIN (-6125 4975) $PN V5
J 2
(-6135 4985);
DISPLAY 0.489362 (-6135 4985);
PAINT MONO (-6135 4985);
FORCEPROP 0 LASTPIN (-6125 4925) $PN V8
J 2
(-6135 4935);
DISPLAY 0.489362 (-6135 4935);
PAINT MONO (-6135 4935);
FORCEPROP 0 LASTPIN (-6125 4875) $PN V10
J 2
(-6135 4885);
DISPLAY 0.489362 (-6135 4885);
PAINT MONO (-6135 4885);
FORCEPROP 0 LASTPIN (-6125 4825) $PN V12
J 2
(-6135 4835);
DISPLAY 0.489362 (-6135 4835);
PAINT MONO (-6135 4835);
FORCEPROP 0 LASTPIN (-6125 4775) $PN V15
J 2
(-6135 4785);
DISPLAY 0.489362 (-6135 4785);
PAINT MONO (-6135 4785);
FORCEPROP 0 LASTPIN (-6125 4725) $PN V17
J 2
(-6135 4735);
DISPLAY 0.489362 (-6135 4735);
PAINT MONO (-6135 4735);
FORCEPROP 0 LASTPIN (-6125 4675) $PN V19
J 2
(-6135 4685);
DISPLAY 0.489362 (-6135 4685);
PAINT MONO (-6135 4685);
FORCEPROP 0 LASTPIN (-6125 4625) $PN V23
J 2
(-6135 4635);
DISPLAY 0.489362 (-6135 4635);
PAINT MONO (-6135 4635);
FORCEPROP 0 LASTPIN (-6125 4575) $PN V24
J 2
(-6135 4585);
DISPLAY 0.489362 (-6135 4585);
PAINT MONO (-6135 4585);
FORCEPROP 0 LASTPIN (-6125 4525) $PN V25
J 2
(-6135 4535);
DISPLAY 0.489362 (-6135 4535);
PAINT MONO (-6135 4535);
FORCEPROP 0 LASTPIN (-6125 4475) $PN V26
J 2
(-6135 4485);
DISPLAY 0.489362 (-6135 4485);
PAINT MONO (-6135 4485);
FORCEPROP 0 LASTPIN (-6125 4425) $PN V28
J 2
(-6135 4435);
DISPLAY 0.489362 (-6135 4435);
PAINT MONO (-6135 4435);
FORCEPROP 0 LASTPIN (-6125 4375) $PN V29
J 2
(-6135 4385);
DISPLAY 0.489362 (-6135 4385);
PAINT MONO (-6135 4385);
FORCEPROP 0 LASTPIN (-6125 4325) $PN V30
J 2
(-6135 4335);
DISPLAY 0.489362 (-6135 4335);
PAINT MONO (-6135 4335);
FORCEPROP 0 LASTPIN (-6125 4275) $PN V31
J 2
(-6135 4285);
DISPLAY 0.489362 (-6135 4285);
PAINT MONO (-6135 4285);
FORCEPROP 0 LASTPIN (-6125 4225) $PN V32
J 2
(-6135 4235);
DISPLAY 0.489362 (-6135 4235);
PAINT MONO (-6135 4235);
FORCEPROP 0 LASTPIN (-6125 4175) $PN V33
J 2
(-6135 4185);
DISPLAY 0.489362 (-6135 4185);
PAINT MONO (-6135 4185);
FORCEPROP 0 LASTPIN (-6125 4125) $PN V34
J 2
(-6135 4135);
DISPLAY 0.489362 (-6135 4135);
PAINT MONO (-6135 4135);
FORCEPROP 0 LASTPIN (-6125 4075) $PN V37
J 2
(-6135 4085);
DISPLAY 0.489362 (-6135 4085);
PAINT MONO (-6135 4085);
FORCEPROP 0 LASTPIN (-6125 4025) $PN V39
J 2
(-6135 4035);
DISPLAY 0.489362 (-6135 4035);
PAINT MONO (-6135 4035);
FORCEPROP 0 LASTPIN (-6125 3975) $PN V42
J 2
(-6135 3985);
DISPLAY 0.489362 (-6135 3985);
PAINT MONO (-6135 3985);
FORCEPROP 0 LASTPIN (-6125 3925) $PN V43
J 2
(-6135 3935);
DISPLAY 0.489362 (-6135 3935);
PAINT MONO (-6135 3935);
FORCEPROP 0 LASTPIN (-6125 3875) $PN V44
J 2
(-6135 3885);
DISPLAY 0.489362 (-6135 3885);
PAINT MONO (-6135 3885);
FORCEPROP 0 LASTPIN (-6125 3825) $PN V45
J 2
(-6135 3835);
DISPLAY 0.489362 (-6135 3835);
PAINT MONO (-6135 3835);
FORCEPROP 0 LASTPIN (-6125 3775) $PN V46
J 2
(-6135 3785);
DISPLAY 0.489362 (-6135 3785);
PAINT MONO (-6135 3785);
FORCEPROP 0 LASTPIN (-6125 3725) $PN V47
J 2
(-6135 3735);
DISPLAY 0.489362 (-6135 3735);
PAINT MONO (-6135 3735);
FORCEPROP 0 LASTPIN (-6125 3675) $PN V48
J 2
(-6135 3685);
DISPLAY 0.489362 (-6135 3685);
PAINT MONO (-6135 3685);
FORCEPROP 0 LASTPIN (-6125 3625) $PN V49
J 2
(-6135 3635);
DISPLAY 0.489362 (-6135 3635);
PAINT MONO (-6135 3635);
FORCEPROP 0 LASTPIN (-6125 3575) $PN V50
J 2
(-6135 3585);
DISPLAY 0.489362 (-6135 3585);
PAINT MONO (-6135 3585);
FORCEPROP 0 LASTPIN (-6125 3525) $PN V51
J 2
(-6135 3535);
DISPLAY 0.489362 (-6135 3535);
PAINT MONO (-6135 3535);
FORCEPROP 0 LASTPIN (-6125 3475) $PN V52
J 2
(-6135 3485);
DISPLAY 0.489362 (-6135 3485);
PAINT MONO (-6135 3485);
FORCEPROP 0 LASTPIN (-6125 3425) $PN V53
J 2
(-6135 3435);
DISPLAY 0.489362 (-6135 3435);
PAINT MONO (-6135 3435);
FORCEPROP 0 LASTPIN (-6125 3375) $PN V57
J 2
(-6135 3385);
DISPLAY 0.489362 (-6135 3385);
PAINT MONO (-6135 3385);
FORCEPROP 0 LASTPIN (-6125 3325) $PN V59
J 2
(-6135 3335);
DISPLAY 0.489362 (-6135 3335);
PAINT MONO (-6135 3335);
FORCEPROP 0 LASTPIN (-6125 3275) $PN V61
J 2
(-6135 3285);
DISPLAY 0.489362 (-6135 3285);
PAINT MONO (-6135 3285);
FORCEPROP 0 LASTPIN (-6125 3225) $PN V64
J 2
(-6135 3235);
DISPLAY 0.489362 (-6135 3235);
PAINT MONO (-6135 3235);
FORCEPROP 0 LASTPIN (-6125 3175) $PN V66
J 2
(-6135 3185);
DISPLAY 0.489362 (-6135 3185);
PAINT MONO (-6135 3185);
FORCEPROP 0 LASTPIN (-6125 3125) $PN V71
J 2
(-6135 3135);
DISPLAY 0.489362 (-6135 3135);
PAINT MONO (-6135 3135);
FORCEPROP 0 LASTPIN (-6125 3075) $PN V73
J 2
(-6135 3085);
DISPLAY 0.489362 (-6135 3085);
PAINT MONO (-6135 3085);
FORCEPROP 0 LASTPIN (-6125 3025) $PN W1
J 2
(-6135 3035);
DISPLAY 0.489362 (-6135 3035);
PAINT MONO (-6135 3035);
FORCEPROP 0 LASTPIN (-6125 2975) $PN W4
J 2
(-6135 2985);
DISPLAY 0.489362 (-6135 2985);
PAINT MONO (-6135 2985);
FORCEPROP 0 LASTPIN (-6125 2925) $PN W6
J 2
(-6135 2935);
DISPLAY 0.489362 (-6135 2935);
PAINT MONO (-6135 2935);
FORCEPROP 0 LASTPIN (-6125 2875) $PN W8
J 2
(-6135 2885);
DISPLAY 0.489362 (-6135 2885);
PAINT MONO (-6135 2885);
FORCEPROP 0 LASTPIN (-6125 2825) $PN W11
J 2
(-6135 2835);
DISPLAY 0.489362 (-6135 2835);
PAINT MONO (-6135 2835);
FORCEPROP 0 LASTPIN (-6125 2775) $PN W13
J 2
(-6135 2785);
DISPLAY 0.489362 (-6135 2785);
PAINT MONO (-6135 2785);
FORCEPROP 0 LASTPIN (-6125 2725) $PN W15
J 2
(-6135 2735);
DISPLAY 0.489362 (-6135 2735);
PAINT MONO (-6135 2735);
FORCEPROP 0 LASTPIN (-6125 2675) $PN W18
J 2
(-6135 2685);
DISPLAY 0.489362 (-6135 2685);
PAINT MONO (-6135 2685);
FORCEPROP 0 LASTPIN (-6125 2625) $PN W20
J 2
(-6135 2635);
DISPLAY 0.489362 (-6135 2635);
PAINT MONO (-6135 2635);
FORCEPROP 0 LASTPIN (-6125 2575) $PN W22
J 2
(-6135 2585);
DISPLAY 0.489362 (-6135 2585);
PAINT MONO (-6135 2585);
FORCEPROP 0 LASTPIN (-6125 2525) $PN W25
J 2
(-6135 2535);
DISPLAY 0.489362 (-6135 2535);
PAINT MONO (-6135 2535);
FORCEPROP 0 LASTPIN (-6125 2475) $PN W28
J 2
(-6135 2485);
DISPLAY 0.489362 (-6135 2485);
PAINT MONO (-6135 2485);
FORCEPROP 0 LASTPIN (-6125 2425) $PN W34
J 2
(-6135 2435);
DISPLAY 0.489362 (-6135 2435);
PAINT MONO (-6135 2435);
FORCEPROP 0 LASTPIN (-6125 2375) $PN W35
J 2
(-6135 2385);
DISPLAY 0.489362 (-6135 2385);
PAINT MONO (-6135 2385);
FORCEPROP 0 LASTPIN (-6125 2325) $PN W36
J 2
(-6135 2335);
DISPLAY 0.489362 (-6135 2335);
PAINT MONO (-6135 2335);
FORCEPROP 0 LASTPIN (-6125 2275) $PN W40
J 2
(-6135 2285);
DISPLAY 0.489362 (-6135 2285);
PAINT MONO (-6135 2285);
FORCEPROP 0 LASTPIN (-6125 2225) $PN W41
J 2
(-6135 2235);
DISPLAY 0.489362 (-6135 2235);
PAINT MONO (-6135 2235);
FORCEPROP 0 LASTPIN (-6125 2175) $PN W42
J 2
(-6135 2185);
DISPLAY 0.489362 (-6135 2185);
PAINT MONO (-6135 2185);
FORCEPROP 0 LASTPIN (-6125 2125) $PN W45
J 2
(-6135 2135);
DISPLAY 0.489362 (-6135 2135);
PAINT MONO (-6135 2135);
FORCEPROP 0 LASTPIN (-6125 2075) $PN W48
J 2
(-6135 2085);
DISPLAY 0.489362 (-6135 2085);
PAINT MONO (-6135 2085);
FORCEPROP 0 LASTPIN (-6125 2025) $PN W51
J 2
(-6135 2035);
DISPLAY 0.489362 (-6135 2035);
PAINT MONO (-6135 2035);
FORCEPROP 0 LASTPIN (-6125 1975) $PN W54
J 2
(-6135 1985);
DISPLAY 0.489362 (-6135 1985);
PAINT MONO (-6135 1985);
FORCEPROP 0 LASTPIN (-6125 1925) $PN W56
J 2
(-6135 1935);
DISPLAY 0.489362 (-6135 1935);
PAINT MONO (-6135 1935);
FORCEPROP 0 LASTPIN (-6125 1875) $PN W58
J 2
(-6135 1885);
DISPLAY 0.489362 (-6135 1885);
PAINT MONO (-6135 1885);
FORCEPROP 0 LASTPIN (-6125 1825) $PN W61
J 2
(-6135 1835);
DISPLAY 0.489362 (-6135 1835);
PAINT MONO (-6135 1835);
FORCEPROP 0 LASTPIN (-6125 1775) $PN W63
J 2
(-6135 1785);
DISPLAY 0.489362 (-6135 1785);
PAINT MONO (-6135 1785);
FORCEPROP 0 LASTPIN (-6125 1725) $PN W65
J 2
(-6135 1735);
DISPLAY 0.489362 (-6135 1735);
PAINT MONO (-6135 1735);
FORCEPROP 0 LASTPIN (-6125 1675) $PN W68
J 2
(-6135 1685);
DISPLAY 0.489362 (-6135 1685);
PAINT MONO (-6135 1685);
FORCEPROP 0 LASTPIN (-6125 1625) $PN W70
J 2
(-6135 1635);
DISPLAY 0.489362 (-6135 1635);
PAINT MONO (-6135 1635);
FORCEPROP 0 LASTPIN (-6125 1575) $PN W72
J 2
(-6135 1585);
DISPLAY 0.489362 (-6135 1585);
PAINT MONO (-6135 1585);
FORCEPROP 0 LASTPIN (-6125 1525) $PN W75
J 2
(-6135 1535);
DISPLAY 0.489362 (-6135 1535);
PAINT MONO (-6135 1535);
FORCEPROP 0 LASTPIN (-6125 1475) $PN Y3
J 2
(-6135 1485);
DISPLAY 0.489362 (-6135 1485);
PAINT MONO (-6135 1485);
FORCEPROP 0 LASTPIN (-6125 1425) $PN Y8
J 2
(-6135 1435);
DISPLAY 0.489362 (-6135 1435);
PAINT MONO (-6135 1435);
FORCEPROP 0 LASTPIN (-6125 1375) $PN Y10
J 2
(-6135 1385);
DISPLAY 0.489362 (-6135 1385);
PAINT MONO (-6135 1385);
FORCEPROP 0 LASTPIN (-6125 1325) $PN Y15
J 2
(-6135 1335);
DISPLAY 0.489362 (-6135 1335);
PAINT MONO (-6135 1335);
FORCEPROP 0 LASTPIN (-6125 1275) $PN Y17
J 2
(-6135 1285);
DISPLAY 0.489362 (-6135 1285);
PAINT MONO (-6135 1285);
FORCEPROP 0 LASTPIN (-6125 1225) $PN Y22
J 2
(-6135 1235);
DISPLAY 0.489362 (-6135 1235);
PAINT MONO (-6135 1235);
FORCEPROP 0 LASTPIN (-6125 1175) $PN Y23
J 2
(-6135 1185);
DISPLAY 0.489362 (-6135 1185);
PAINT MONO (-6135 1185);
FORCEPROP 0 LASTPIN (-6125 1125) $PN Y24
J 2
(-6135 1135);
DISPLAY 0.489362 (-6135 1135);
PAINT MONO (-6135 1135);
FORCEPROP 0 LASTPIN (-6125 1075) $PN Y25
J 2
(-6135 1085);
DISPLAY 0.489362 (-6135 1085);
PAINT MONO (-6135 1085);
FORCEPROP 0 LASTPIN (-6125 1025) $PN Y26
J 2
(-6135 1035);
DISPLAY 0.489362 (-6135 1035);
PAINT MONO (-6135 1035);
FORCEPROP 0 LASTPIN (-6125 975) $PN Y27
J 2
(-6135 985);
DISPLAY 0.489362 (-6135 985);
PAINT MONO (-6135 985);
FORCEPROP 0 LASTPIN (-6125 925) $PN Y28
J 2
(-6135 935);
DISPLAY 0.489362 (-6135 935);
PAINT MONO (-6135 935);
FORCEPROP 0 LASTPIN (-6125 875) $PN Y31
J 2
(-6135 885);
DISPLAY 0.489362 (-6135 885);
PAINT MONO (-6135 885);
FORCEPROP 0 LASTPIN (-6125 825) $PN Y32
J 2
(-6135 835);
DISPLAY 0.489362 (-6135 835);
PAINT MONO (-6135 835);
FORCEPROP 0 LASTPIN (-6125 775) $PN Y33
J 2
(-6135 785);
DISPLAY 0.489362 (-6135 785);
PAINT MONO (-6135 785);
FORCEPROP 0 LASTPIN (-6125 725) $PN Y34
J 2
(-6135 735);
DISPLAY 0.489362 (-6135 735);
PAINT MONO (-6135 735);
FORCEPROP 0 LASTPIN (-6125 675) $PN Y37
J 2
(-6135 685);
DISPLAY 0.489362 (-6135 685);
PAINT MONO (-6135 685);
FORCEPROP 0 LASTPIN (-6125 625) $PN Y39
J 2
(-6135 635);
DISPLAY 0.489362 (-6135 635);
PAINT MONO (-6135 635);
FORCEPROP 0 LASTPIN (-6125 575) $PN Y42
J 2
(-6135 585);
DISPLAY 0.489362 (-6135 585);
PAINT MONO (-6135 585);
FORCEPROP 0 LASTPIN (-6125 525) $PN Y43
J 2
(-6135 535);
DISPLAY 0.489362 (-6135 535);
PAINT MONO (-6135 535);
FORCEPROP 0 LASTPIN (-5025 6325) $PN Y44
J 0
(-5015 6335);
DISPLAY 0.489362 (-5015 6335);
PAINT MONO (-5015 6335);
FORCEPROP 0 LASTPIN (-5025 6275) $PN Y45
J 0
(-5015 6285);
DISPLAY 0.489362 (-5015 6285);
PAINT MONO (-5015 6285);
FORCEPROP 0 LASTPIN (-5025 6225) $PN Y48
J 0
(-5015 6235);
DISPLAY 0.489362 (-5015 6235);
PAINT MONO (-5015 6235);
FORCEPROP 0 LASTPIN (-5025 6175) $PN Y49
J 0
(-5015 6185);
DISPLAY 0.489362 (-5015 6185);
PAINT MONO (-5015 6185);
FORCEPROP 0 LASTPIN (-5025 6125) $PN Y50
J 0
(-5015 6135);
DISPLAY 0.489362 (-5015 6135);
PAINT MONO (-5015 6135);
FORCEPROP 0 LASTPIN (-5025 6075) $PN Y51
J 0
(-5015 6085);
DISPLAY 0.489362 (-5015 6085);
PAINT MONO (-5015 6085);
FORCEPROP 0 LASTPIN (-5025 6025) $PN Y52
J 0
(-5015 6035);
DISPLAY 0.489362 (-5015 6035);
PAINT MONO (-5015 6035);
FORCEPROP 0 LASTPIN (-5025 5975) $PN Y53
J 0
(-5015 5985);
DISPLAY 0.489362 (-5015 5985);
PAINT MONO (-5015 5985);
FORCEPROP 0 LASTPIN (-5025 5925) $PN Y54
J 0
(-5015 5935);
DISPLAY 0.489362 (-5015 5935);
PAINT MONO (-5015 5935);
FORCEPROP 0 LASTPIN (-5025 5875) $PN Y59
J 0
(-5015 5885);
DISPLAY 0.489362 (-5015 5885);
PAINT MONO (-5015 5885);
FORCEPROP 0 LASTPIN (-5025 5825) $PN Y61
J 0
(-5015 5835);
DISPLAY 0.489362 (-5015 5835);
PAINT MONO (-5015 5835);
FORCEPROP 0 LASTPIN (-5025 5775) $PN Y66
J 0
(-5015 5785);
DISPLAY 0.489362 (-5015 5785);
PAINT MONO (-5015 5785);
FORCEPROP 0 LASTPIN (-5025 5725) $PN Y68
J 0
(-5015 5735);
DISPLAY 0.489362 (-5015 5735);
PAINT MONO (-5015 5735);
FORCEPROP 0 LASTPIN (-5025 5675) $PN Y73
J 0
(-5015 5685);
DISPLAY 0.489362 (-5015 5685);
PAINT MONO (-5015 5685);
FORCEPROP 2 LAST PART_TYPE SMLF
J 0
(-5975 6725);
DISPLAY 1.021277 (-5975 6725);
FORCEPROP 1 LAST MATERIAL IO
J 0
(-5970 6557);
DISPLAY 0.489362 (-5970 6557);
PAINT SKYBLUE (-5970 6557);
FORCEPROP 2 LAST VALUE SOCKET6096_13568-001
J 0
(-5975 6600);
DISPLAY 0.489362 (-5975 6600);
PAINT SKYBLUE (-5975 6600);
FORCEPROP 2 LAST CDS_LIB pure_quanta
J 0
(-5575 3475);
DISPLAY INVISIBLE (-5575 3475);
FORCEPROP 1 LAST CDS_LMAN_SYM_OUTLINE -400,3050,400,-3050
J 0
(-5575 3475);
DISPLAY 0.468085 (-5575 3475);
PAINT GREEN (-5575 3475);
DISPLAY INVISIBLE (-5575 3475);
FORCEPROP 1 LAST NEEDS_NO_SIZE TRUE
J 0
(-5575 3475);
DISPLAY 0.723404 (-5575 3475);
PAINT GREEN (-5575 3475);
DISPLAY INVISIBLE (-5575 3475);
FORCEPROP 1 LAST PATH I12
J 0
(-5575 3475);
DISPLAY 0.723404 (-5575 3475);
PAINT GREEN (-5575 3475);
DISPLAY INVISIBLE (-5575 3475);
FORCEPROP 1 LAST PART_NUMBER DGA^6000030
J 0
(-5970 6684);
DISPLAY 0.489362 (-5970 6684);
PAINT SKYBLUE (-5970 6684);
DISPLAY INVISIBLE (-5970 6684);
FORCEADD GENOA_SP5..29
(-7050 3450);
FORCEPROP 1 LAST LOCATION U26
J 0
(-7450 6625);
DISPLAY 0.489362 (-7450 6625);
PAINT SKYBLUE (-7450 6625);
FORCEPROP 0 LAST $SEC 29
J 0
(-7425 6850);
DISPLAY 0.680851 (-7425 6850);
PAINT MONO (-7425 6850);
DISPLAY INVISIBLE (-7425 6850);
FORCEPROP 0 LAST CDS_SEC 29
J 0
(-7425 6850);
DISPLAY 1.021277 (-7425 6850);
DISPLAY INVISIBLE (-7425 6850);
FORCEPROP 0 LASTPIN (-7600 6300) $PN J15
J 2
(-7610 6310);
DISPLAY 0.489362 (-7610 6310);
PAINT MONO (-7610 6310);
FORCEPROP 0 LASTPIN (-7600 6250) $PN J18
J 2
(-7610 6260);
DISPLAY 0.489362 (-7610 6260);
PAINT MONO (-7610 6260);
FORCEPROP 0 LASTPIN (-7600 6200) $PN J20
J 2
(-7610 6210);
DISPLAY 0.489362 (-7610 6210);
PAINT MONO (-7610 6210);
FORCEPROP 0 LASTPIN (-7600 6150) $PN J22
J 2
(-7610 6160);
DISPLAY 0.489362 (-7610 6160);
PAINT MONO (-7610 6160);
FORCEPROP 0 LASTPIN (-7600 6100) $PN J25
J 2
(-7610 6110);
DISPLAY 0.489362 (-7610 6110);
PAINT MONO (-7610 6110);
FORCEPROP 0 LASTPIN (-7600 6050) $PN J28
J 2
(-7610 6060);
DISPLAY 0.489362 (-7610 6060);
PAINT MONO (-7610 6060);
FORCEPROP 0 LASTPIN (-7600 6000) $PN J31
J 2
(-7610 6010);
DISPLAY 0.489362 (-7610 6010);
PAINT MONO (-7610 6010);
FORCEPROP 0 LASTPIN (-7600 5950) $PN J34
J 2
(-7610 5960);
DISPLAY 0.489362 (-7610 5960);
PAINT MONO (-7610 5960);
FORCEPROP 0 LASTPIN (-7600 5900) $PN J42
J 2
(-7610 5910);
DISPLAY 0.489362 (-7610 5910);
PAINT MONO (-7610 5910);
FORCEPROP 0 LASTPIN (-7600 5850) $PN J45
J 2
(-7610 5860);
DISPLAY 0.489362 (-7610 5860);
PAINT MONO (-7610 5860);
FORCEPROP 0 LASTPIN (-7600 5800) $PN J48
J 2
(-7610 5810);
DISPLAY 0.489362 (-7610 5810);
PAINT MONO (-7610 5810);
FORCEPROP 0 LASTPIN (-7600 5750) $PN J51
J 2
(-7610 5760);
DISPLAY 0.489362 (-7610 5760);
PAINT MONO (-7610 5760);
FORCEPROP 0 LASTPIN (-7600 5700) $PN J54
J 2
(-7610 5710);
DISPLAY 0.489362 (-7610 5710);
PAINT MONO (-7610 5710);
FORCEPROP 0 LASTPIN (-7600 5650) $PN J56
J 2
(-7610 5660);
DISPLAY 0.489362 (-7610 5660);
PAINT MONO (-7610 5660);
FORCEPROP 0 LASTPIN (-7600 5600) $PN J58
J 2
(-7610 5610);
DISPLAY 0.489362 (-7610 5610);
PAINT MONO (-7610 5610);
FORCEPROP 0 LASTPIN (-7600 5550) $PN J61
J 2
(-7610 5560);
DISPLAY 0.489362 (-7610 5560);
PAINT MONO (-7610 5560);
FORCEPROP 0 LASTPIN (-7600 5500) $PN J63
J 2
(-7610 5510);
DISPLAY 0.489362 (-7610 5510);
PAINT MONO (-7610 5510);
FORCEPROP 0 LASTPIN (-7600 5450) $PN J65
J 2
(-7610 5460);
DISPLAY 0.489362 (-7610 5460);
PAINT MONO (-7610 5460);
FORCEPROP 0 LASTPIN (-7600 5400) $PN J68
J 2
(-7610 5410);
DISPLAY 0.489362 (-7610 5410);
PAINT MONO (-7610 5410);
FORCEPROP 0 LASTPIN (-7600 5350) $PN J70
J 2
(-7610 5360);
DISPLAY 0.489362 (-7610 5360);
PAINT MONO (-7610 5360);
FORCEPROP 0 LASTPIN (-7600 5300) $PN J72
J 2
(-7610 5310);
DISPLAY 0.489362 (-7610 5310);
PAINT MONO (-7610 5310);
FORCEPROP 0 LASTPIN (-7600 5250) $PN J75
J 2
(-7610 5260);
DISPLAY 0.489362 (-7610 5260);
PAINT MONO (-7610 5260);
FORCEPROP 0 LASTPIN (-7600 5200) $PN K3
J 2
(-7610 5210);
DISPLAY 0.489362 (-7610 5210);
PAINT MONO (-7610 5210);
FORCEPROP 0 LASTPIN (-7600 5150) $PN K5
J 2
(-7610 5160);
DISPLAY 0.489362 (-7610 5160);
PAINT MONO (-7610 5160);
FORCEPROP 0 LASTPIN (-7600 5100) $PN K8
J 2
(-7610 5110);
DISPLAY 0.489362 (-7610 5110);
PAINT MONO (-7610 5110);
FORCEPROP 0 LASTPIN (-7600 5050) $PN K10
J 2
(-7610 5060);
DISPLAY 0.489362 (-7610 5060);
PAINT MONO (-7610 5060);
FORCEPROP 0 LASTPIN (-7600 5000) $PN K12
J 2
(-7610 5010);
DISPLAY 0.489362 (-7610 5010);
PAINT MONO (-7610 5010);
FORCEPROP 0 LASTPIN (-7600 4950) $PN K15
J 2
(-7610 4960);
DISPLAY 0.489362 (-7610 4960);
PAINT MONO (-7610 4960);
FORCEPROP 0 LASTPIN (-7600 4900) $PN K17
J 2
(-7610 4910);
DISPLAY 0.489362 (-7610 4910);
PAINT MONO (-7610 4910);
FORCEPROP 0 LASTPIN (-7600 4850) $PN K19
J 2
(-7610 4860);
DISPLAY 0.489362 (-7610 4860);
PAINT MONO (-7610 4860);
FORCEPROP 0 LASTPIN (-7600 4800) $PN K24
J 2
(-7610 4810);
DISPLAY 0.489362 (-7610 4810);
PAINT MONO (-7610 4810);
FORCEPROP 0 LASTPIN (-7600 4750) $PN K25
J 2
(-7610 4760);
DISPLAY 0.489362 (-7610 4760);
PAINT MONO (-7610 4760);
FORCEPROP 0 LASTPIN (-7600 4700) $PN K26
J 2
(-7610 4710);
DISPLAY 0.489362 (-7610 4710);
PAINT MONO (-7610 4710);
FORCEPROP 0 LASTPIN (-7600 4650) $PN K27
J 2
(-7610 4660);
DISPLAY 0.489362 (-7610 4660);
PAINT MONO (-7610 4660);
FORCEPROP 0 LASTPIN (-7600 4600) $PN K28
J 2
(-7610 4610);
DISPLAY 0.489362 (-7610 4610);
PAINT MONO (-7610 4610);
FORCEPROP 0 LASTPIN (-7600 4550) $PN K29
J 2
(-7610 4560);
DISPLAY 0.489362 (-7610 4560);
PAINT MONO (-7610 4560);
FORCEPROP 0 LASTPIN (-7600 4500) $PN K30
J 2
(-7610 4510);
DISPLAY 0.489362 (-7610 4510);
PAINT MONO (-7610 4510);
FORCEPROP 0 LASTPIN (-7600 4450) $PN K31
J 2
(-7610 4460);
DISPLAY 0.489362 (-7610 4460);
PAINT MONO (-7610 4460);
FORCEPROP 0 LASTPIN (-7600 4400) $PN K32
J 2
(-7610 4410);
DISPLAY 0.489362 (-7610 4410);
PAINT MONO (-7610 4410);
FORCEPROP 0 LASTPIN (-7600 4350) $PN K33
J 2
(-7610 4360);
DISPLAY 0.489362 (-7610 4360);
PAINT MONO (-7610 4360);
FORCEPROP 0 LASTPIN (-7600 4300) $PN K34
J 2
(-7610 4310);
DISPLAY 0.489362 (-7610 4310);
PAINT MONO (-7610 4310);
FORCEPROP 0 LASTPIN (-7600 4250) $PN K37
J 2
(-7610 4260);
DISPLAY 0.489362 (-7610 4260);
PAINT MONO (-7610 4260);
FORCEPROP 0 LASTPIN (-7600 4200) $PN K39
J 2
(-7610 4210);
DISPLAY 0.489362 (-7610 4210);
PAINT MONO (-7610 4210);
FORCEPROP 0 LASTPIN (-7600 4150) $PN K42
J 2
(-7610 4160);
DISPLAY 0.489362 (-7610 4160);
PAINT MONO (-7610 4160);
FORCEPROP 0 LASTPIN (-7600 4100) $PN K43
J 2
(-7610 4110);
DISPLAY 0.489362 (-7610 4110);
PAINT MONO (-7610 4110);
FORCEPROP 0 LASTPIN (-7600 4050) $PN K44
J 2
(-7610 4060);
DISPLAY 0.489362 (-7610 4060);
PAINT MONO (-7610 4060);
FORCEPROP 0 LASTPIN (-7600 4000) $PN K45
J 2
(-7610 4010);
DISPLAY 0.489362 (-7610 4010);
PAINT MONO (-7610 4010);
FORCEPROP 0 LASTPIN (-7600 3950) $PN K46
J 2
(-7610 3960);
DISPLAY 0.489362 (-7610 3960);
PAINT MONO (-7610 3960);
FORCEPROP 0 LASTPIN (-7600 3900) $PN K47
J 2
(-7610 3910);
DISPLAY 0.489362 (-7610 3910);
PAINT MONO (-7610 3910);
FORCEPROP 0 LASTPIN (-7600 3850) $PN K48
J 2
(-7610 3860);
DISPLAY 0.489362 (-7610 3860);
PAINT MONO (-7610 3860);
FORCEPROP 0 LASTPIN (-7600 3800) $PN K49
J 2
(-7610 3810);
DISPLAY 0.489362 (-7610 3810);
PAINT MONO (-7610 3810);
FORCEPROP 0 LASTPIN (-7600 3750) $PN K50
J 2
(-7610 3760);
DISPLAY 0.489362 (-7610 3760);
PAINT MONO (-7610 3760);
FORCEPROP 0 LASTPIN (-7600 3700) $PN K51
J 2
(-7610 3710);
DISPLAY 0.489362 (-7610 3710);
PAINT MONO (-7610 3710);
FORCEPROP 0 LASTPIN (-7600 3650) $PN K52
J 2
(-7610 3660);
DISPLAY 0.489362 (-7610 3660);
PAINT MONO (-7610 3660);
FORCEPROP 0 LASTPIN (-7600 3600) $PN K53
J 2
(-7610 3610);
DISPLAY 0.489362 (-7610 3610);
PAINT MONO (-7610 3610);
FORCEPROP 0 LASTPIN (-7600 3550) $PN K57
J 2
(-7610 3560);
DISPLAY 0.489362 (-7610 3560);
PAINT MONO (-7610 3560);
FORCEPROP 0 LASTPIN (-7600 3500) $PN K61
J 2
(-7610 3510);
DISPLAY 0.489362 (-7610 3510);
PAINT MONO (-7610 3510);
FORCEPROP 0 LASTPIN (-7600 3450) $PN K64
J 2
(-7610 3460);
DISPLAY 0.489362 (-7610 3460);
PAINT MONO (-7610 3460);
FORCEPROP 0 LASTPIN (-7600 3400) $PN K66
J 2
(-7610 3410);
DISPLAY 0.489362 (-7610 3410);
PAINT MONO (-7610 3410);
FORCEPROP 0 LASTPIN (-7600 3350) $PN K68
J 2
(-7610 3360);
DISPLAY 0.489362 (-7610 3360);
PAINT MONO (-7610 3360);
FORCEPROP 0 LASTPIN (-7600 3300) $PN K71
J 2
(-7610 3310);
DISPLAY 0.489362 (-7610 3310);
PAINT MONO (-7610 3310);
FORCEPROP 0 LASTPIN (-7600 3250) $PN K73
J 2
(-7610 3260);
DISPLAY 0.489362 (-7610 3260);
PAINT MONO (-7610 3260);
FORCEPROP 0 LASTPIN (-7600 3200) $PN L1
J 2
(-7610 3210);
DISPLAY 0.489362 (-7610 3210);
PAINT MONO (-7610 3210);
FORCEPROP 0 LASTPIN (-7600 3150) $PN L6
J 2
(-7610 3160);
DISPLAY 0.489362 (-7610 3160);
PAINT MONO (-7610 3160);
FORCEPROP 0 LASTPIN (-7600 3100) $PN L8
J 2
(-7610 3110);
DISPLAY 0.489362 (-7610 3110);
PAINT MONO (-7610 3110);
FORCEPROP 0 LASTPIN (-7600 3050) $PN L13
J 2
(-7610 3060);
DISPLAY 0.489362 (-7610 3060);
PAINT MONO (-7610 3060);
FORCEPROP 0 LASTPIN (-7600 3000) $PN L15
J 2
(-7610 3010);
DISPLAY 0.489362 (-7610 3010);
PAINT MONO (-7610 3010);
FORCEPROP 0 LASTPIN (-7600 2950) $PN L20
J 2
(-7610 2960);
DISPLAY 0.489362 (-7610 2960);
PAINT MONO (-7610 2960);
FORCEPROP 0 LASTPIN (-7600 2900) $PN L22
J 2
(-7610 2910);
DISPLAY 0.489362 (-7610 2910);
PAINT MONO (-7610 2910);
FORCEPROP 0 LASTPIN (-7600 2850) $PN L25
J 2
(-7610 2860);
DISPLAY 0.489362 (-7610 2860);
PAINT MONO (-7610 2860);
FORCEPROP 0 LASTPIN (-7600 2800) $PN L28
J 2
(-7610 2810);
DISPLAY 0.489362 (-7610 2810);
PAINT MONO (-7610 2810);
FORCEPROP 0 LASTPIN (-7600 2750) $PN L31
J 2
(-7610 2760);
DISPLAY 0.489362 (-7610 2760);
PAINT MONO (-7610 2760);
FORCEPROP 0 LASTPIN (-7600 2700) $PN L34
J 2
(-7610 2710);
DISPLAY 0.489362 (-7610 2710);
PAINT MONO (-7610 2710);
FORCEPROP 0 LASTPIN (-7600 2650) $PN L35
J 2
(-7610 2660);
DISPLAY 0.489362 (-7610 2660);
PAINT MONO (-7610 2660);
FORCEPROP 0 LASTPIN (-7600 2600) $PN L36
J 2
(-7610 2610);
DISPLAY 0.489362 (-7610 2610);
PAINT MONO (-7610 2610);
FORCEPROP 0 LASTPIN (-7600 2550) $PN L40
J 2
(-7610 2560);
DISPLAY 0.489362 (-7610 2560);
PAINT MONO (-7610 2560);
FORCEPROP 0 LASTPIN (-7600 2500) $PN L41
J 2
(-7610 2510);
DISPLAY 0.489362 (-7610 2510);
PAINT MONO (-7610 2510);
FORCEPROP 0 LASTPIN (-7600 2450) $PN L42
J 2
(-7610 2460);
DISPLAY 0.489362 (-7610 2460);
PAINT MONO (-7610 2460);
FORCEPROP 0 LASTPIN (-7600 2400) $PN L45
J 2
(-7610 2410);
DISPLAY 0.489362 (-7610 2410);
PAINT MONO (-7610 2410);
FORCEPROP 0 LASTPIN (-7600 2350) $PN L48
J 2
(-7610 2360);
DISPLAY 0.489362 (-7610 2360);
PAINT MONO (-7610 2360);
FORCEPROP 0 LASTPIN (-7600 2300) $PN L51
J 2
(-7610 2310);
DISPLAY 0.489362 (-7610 2310);
PAINT MONO (-7610 2310);
FORCEPROP 0 LASTPIN (-7600 2250) $PN L54
J 2
(-7610 2260);
DISPLAY 0.489362 (-7610 2260);
PAINT MONO (-7610 2260);
FORCEPROP 0 LASTPIN (-7600 2200) $PN L56
J 2
(-7610 2210);
DISPLAY 0.489362 (-7610 2210);
PAINT MONO (-7610 2210);
FORCEPROP 0 LASTPIN (-7600 2150) $PN L61
J 2
(-7610 2160);
DISPLAY 0.489362 (-7610 2160);
PAINT MONO (-7610 2160);
FORCEPROP 0 LASTPIN (-7600 2100) $PN L63
J 2
(-7610 2110);
DISPLAY 0.489362 (-7610 2110);
PAINT MONO (-7610 2110);
FORCEPROP 0 LASTPIN (-7600 2050) $PN L68
J 2
(-7610 2060);
DISPLAY 0.489362 (-7610 2060);
PAINT MONO (-7610 2060);
FORCEPROP 0 LASTPIN (-7600 2000) $PN L70
J 2
(-7610 2010);
DISPLAY 0.489362 (-7610 2010);
PAINT MONO (-7610 2010);
FORCEPROP 0 LASTPIN (-7600 1950) $PN L75
J 2
(-7610 1960);
DISPLAY 0.489362 (-7610 1960);
PAINT MONO (-7610 1960);
FORCEPROP 0 LASTPIN (-7600 1900) $PN M3
J 2
(-7610 1910);
DISPLAY 0.489362 (-7610 1910);
PAINT MONO (-7610 1910);
FORCEPROP 0 LASTPIN (-7600 1850) $PN M5
J 2
(-7610 1860);
DISPLAY 0.489362 (-7610 1860);
PAINT MONO (-7610 1860);
FORCEPROP 0 LASTPIN (-7600 1800) $PN M8
J 2
(-7610 1810);
DISPLAY 0.489362 (-7610 1810);
PAINT MONO (-7610 1810);
FORCEPROP 0 LASTPIN (-7600 1750) $PN M10
J 2
(-7610 1760);
DISPLAY 0.489362 (-7610 1760);
PAINT MONO (-7610 1760);
FORCEPROP 0 LASTPIN (-7600 1700) $PN M12
J 2
(-7610 1710);
DISPLAY 0.489362 (-7610 1710);
PAINT MONO (-7610 1710);
FORCEPROP 0 LASTPIN (-7600 1650) $PN M15
J 2
(-7610 1660);
DISPLAY 0.489362 (-7610 1660);
PAINT MONO (-7610 1660);
FORCEPROP 0 LASTPIN (-7600 1600) $PN M17
J 2
(-7610 1610);
DISPLAY 0.489362 (-7610 1610);
PAINT MONO (-7610 1610);
FORCEPROP 0 LASTPIN (-7600 1550) $PN M19
J 2
(-7610 1560);
DISPLAY 0.489362 (-7610 1560);
PAINT MONO (-7610 1560);
FORCEPROP 0 LASTPIN (-7600 1500) $PN M22
J 2
(-7610 1510);
DISPLAY 0.489362 (-7610 1510);
PAINT MONO (-7610 1510);
FORCEPROP 0 LASTPIN (-7600 1450) $PN M25
J 2
(-7610 1460);
DISPLAY 0.489362 (-7610 1460);
PAINT MONO (-7610 1460);
FORCEPROP 0 LASTPIN (-7600 1400) $PN M28
J 2
(-7610 1410);
DISPLAY 0.489362 (-7610 1410);
PAINT MONO (-7610 1410);
FORCEPROP 0 LASTPIN (-7600 1350) $PN M31
J 2
(-7610 1360);
DISPLAY 0.489362 (-7610 1360);
PAINT MONO (-7610 1360);
FORCEPROP 0 LASTPIN (-7600 1300) $PN M34
J 2
(-7610 1310);
DISPLAY 0.489362 (-7610 1310);
PAINT MONO (-7610 1310);
FORCEPROP 0 LASTPIN (-7600 1250) $PN M37
J 2
(-7610 1260);
DISPLAY 0.489362 (-7610 1260);
PAINT MONO (-7610 1260);
FORCEPROP 0 LASTPIN (-7600 1200) $PN M39
J 2
(-7610 1210);
DISPLAY 0.489362 (-7610 1210);
PAINT MONO (-7610 1210);
FORCEPROP 0 LASTPIN (-7600 1150) $PN M42
J 2
(-7610 1160);
DISPLAY 0.489362 (-7610 1160);
PAINT MONO (-7610 1160);
FORCEPROP 0 LASTPIN (-7600 1100) $PN M45
J 2
(-7610 1110);
DISPLAY 0.489362 (-7610 1110);
PAINT MONO (-7610 1110);
FORCEPROP 0 LASTPIN (-7600 1050) $PN M48
J 2
(-7610 1060);
DISPLAY 0.489362 (-7610 1060);
PAINT MONO (-7610 1060);
FORCEPROP 0 LASTPIN (-7600 1000) $PN M51
J 2
(-7610 1010);
DISPLAY 0.489362 (-7610 1010);
PAINT MONO (-7610 1010);
FORCEPROP 0 LASTPIN (-7600 950) $PN M54
J 2
(-7610 960);
DISPLAY 0.489362 (-7610 960);
PAINT MONO (-7610 960);
FORCEPROP 0 LASTPIN (-7600 900) $PN M57
J 2
(-7610 910);
DISPLAY 0.489362 (-7610 910);
PAINT MONO (-7610 910);
FORCEPROP 0 LASTPIN (-7600 850) $PN M59
J 2
(-7610 860);
DISPLAY 0.489362 (-7610 860);
PAINT MONO (-7610 860);
FORCEPROP 0 LASTPIN (-7600 800) $PN M61
J 2
(-7610 810);
DISPLAY 0.489362 (-7610 810);
PAINT MONO (-7610 810);
FORCEPROP 0 LASTPIN (-7600 750) $PN M64
J 2
(-7610 760);
DISPLAY 0.489362 (-7610 760);
PAINT MONO (-7610 760);
FORCEPROP 0 LASTPIN (-7600 700) $PN M66
J 2
(-7610 710);
DISPLAY 0.489362 (-7610 710);
PAINT MONO (-7610 710);
FORCEPROP 0 LASTPIN (-7600 650) $PN M68
J 2
(-7610 660);
DISPLAY 0.489362 (-7610 660);
PAINT MONO (-7610 660);
FORCEPROP 0 LASTPIN (-7600 600) $PN M71
J 2
(-7610 610);
DISPLAY 0.489362 (-7610 610);
PAINT MONO (-7610 610);
FORCEPROP 0 LASTPIN (-7600 550) $PN M73
J 2
(-7610 560);
DISPLAY 0.489362 (-7610 560);
PAINT MONO (-7610 560);
FORCEPROP 0 LASTPIN (-7600 500) $PN N1
J 2
(-7610 510);
DISPLAY 0.489362 (-7610 510);
PAINT MONO (-7610 510);
FORCEPROP 0 LASTPIN (-6500 6300) $PN N4
J 0
(-6490 6310);
DISPLAY 0.489362 (-6490 6310);
PAINT MONO (-6490 6310);
FORCEPROP 0 LASTPIN (-6500 6250) $PN N6
J 0
(-6490 6260);
DISPLAY 0.489362 (-6490 6260);
PAINT MONO (-6490 6260);
FORCEPROP 0 LASTPIN (-6500 6200) $PN N8
J 0
(-6490 6210);
DISPLAY 0.489362 (-6490 6210);
PAINT MONO (-6490 6210);
FORCEPROP 0 LASTPIN (-6500 6150) $PN N11
J 0
(-6490 6160);
DISPLAY 0.489362 (-6490 6160);
PAINT MONO (-6490 6160);
FORCEPROP 0 LASTPIN (-6500 6100) $PN N13
J 0
(-6490 6110);
DISPLAY 0.489362 (-6490 6110);
PAINT MONO (-6490 6110);
FORCEPROP 0 LASTPIN (-6500 6050) $PN N15
J 0
(-6490 6060);
DISPLAY 0.489362 (-6490 6060);
PAINT MONO (-6490 6060);
FORCEPROP 0 LASTPIN (-6500 6000) $PN N18
J 0
(-6490 6010);
DISPLAY 0.489362 (-6490 6010);
PAINT MONO (-6490 6010);
FORCEPROP 0 LASTPIN (-6500 5950) $PN N20
J 0
(-6490 5960);
DISPLAY 0.489362 (-6490 5960);
PAINT MONO (-6490 5960);
FORCEPROP 0 LASTPIN (-6500 5900) $PN N22
J 0
(-6490 5910);
DISPLAY 0.489362 (-6490 5910);
PAINT MONO (-6490 5910);
FORCEPROP 0 LASTPIN (-6500 5850) $PN N25
J 0
(-6490 5860);
DISPLAY 0.489362 (-6490 5860);
PAINT MONO (-6490 5860);
FORCEPROP 0 LASTPIN (-6500 5800) $PN N28
J 0
(-6490 5810);
DISPLAY 0.489362 (-6490 5810);
PAINT MONO (-6490 5810);
FORCEPROP 0 LASTPIN (-6500 5750) $PN N31
J 0
(-6490 5760);
DISPLAY 0.489362 (-6490 5760);
PAINT MONO (-6490 5760);
FORCEPROP 0 LASTPIN (-6500 5700) $PN N34
J 0
(-6490 5710);
DISPLAY 0.489362 (-6490 5710);
PAINT MONO (-6490 5710);
FORCEPROP 0 LASTPIN (-6500 5650) $PN N42
J 0
(-6490 5660);
DISPLAY 0.489362 (-6490 5660);
PAINT MONO (-6490 5660);
FORCEPROP 0 LASTPIN (-6500 5600) $PN N45
J 0
(-6490 5610);
DISPLAY 0.489362 (-6490 5610);
PAINT MONO (-6490 5610);
FORCEPROP 0 LASTPIN (-6500 5550) $PN N48
J 0
(-6490 5560);
DISPLAY 0.489362 (-6490 5560);
PAINT MONO (-6490 5560);
FORCEPROP 0 LASTPIN (-6500 5500) $PN N51
J 0
(-6490 5510);
DISPLAY 0.489362 (-6490 5510);
PAINT MONO (-6490 5510);
FORCEPROP 0 LASTPIN (-6500 5450) $PN N54
J 0
(-6490 5460);
DISPLAY 0.489362 (-6490 5460);
PAINT MONO (-6490 5460);
FORCEPROP 0 LASTPIN (-6500 5400) $PN N56
J 0
(-6490 5410);
DISPLAY 0.489362 (-6490 5410);
PAINT MONO (-6490 5410);
FORCEPROP 0 LASTPIN (-6500 5350) $PN N58
J 0
(-6490 5360);
DISPLAY 0.489362 (-6490 5360);
PAINT MONO (-6490 5360);
FORCEPROP 0 LASTPIN (-6500 5300) $PN N61
J 0
(-6490 5310);
DISPLAY 0.489362 (-6490 5310);
PAINT MONO (-6490 5310);
FORCEPROP 0 LASTPIN (-6500 5250) $PN N63
J 0
(-6490 5260);
DISPLAY 0.489362 (-6490 5260);
PAINT MONO (-6490 5260);
FORCEPROP 0 LASTPIN (-6500 5200) $PN N65
J 0
(-6490 5210);
DISPLAY 0.489362 (-6490 5210);
PAINT MONO (-6490 5210);
FORCEPROP 0 LASTPIN (-6500 5150) $PN N68
J 0
(-6490 5160);
DISPLAY 0.489362 (-6490 5160);
PAINT MONO (-6490 5160);
FORCEPROP 0 LASTPIN (-6500 5100) $PN N70
J 0
(-6490 5110);
DISPLAY 0.489362 (-6490 5110);
PAINT MONO (-6490 5110);
FORCEPROP 0 LASTPIN (-6500 5050) $PN N72
J 0
(-6490 5060);
DISPLAY 0.489362 (-6490 5060);
PAINT MONO (-6490 5060);
FORCEPROP 0 LASTPIN (-6500 5000) $PN N75
J 0
(-6490 5010);
DISPLAY 0.489362 (-6490 5010);
PAINT MONO (-6490 5010);
FORCEPROP 0 LASTPIN (-6500 4950) $PN P3
J 0
(-6490 4960);
DISPLAY 0.489362 (-6490 4960);
PAINT MONO (-6490 4960);
FORCEPROP 0 LASTPIN (-6500 4900) $PN P8
J 0
(-6490 4910);
DISPLAY 0.489362 (-6490 4910);
PAINT MONO (-6490 4910);
FORCEPROP 0 LASTPIN (-6500 4850) $PN P10
J 0
(-6490 4860);
DISPLAY 0.489362 (-6490 4860);
PAINT MONO (-6490 4860);
FORCEPROP 0 LASTPIN (-6500 4800) $PN P15
J 0
(-6490 4810);
DISPLAY 0.489362 (-6490 4810);
PAINT MONO (-6490 4810);
FORCEPROP 0 LASTPIN (-6500 4750) $PN P17
J 0
(-6490 4760);
DISPLAY 0.489362 (-6490 4760);
PAINT MONO (-6490 4760);
FORCEPROP 0 LASTPIN (-6500 4700) $PN P23
J 0
(-6490 4710);
DISPLAY 0.489362 (-6490 4710);
PAINT MONO (-6490 4710);
FORCEPROP 0 LASTPIN (-6500 4650) $PN P24
J 0
(-6490 4660);
DISPLAY 0.489362 (-6490 4660);
PAINT MONO (-6490 4660);
FORCEPROP 0 LASTPIN (-6500 4600) $PN P26
J 0
(-6490 4610);
DISPLAY 0.489362 (-6490 4610);
PAINT MONO (-6490 4610);
FORCEPROP 0 LASTPIN (-6500 4550) $PN P27
J 0
(-6490 4560);
DISPLAY 0.489362 (-6490 4560);
PAINT MONO (-6490 4560);
FORCEPROP 0 LASTPIN (-6500 4500) $PN P28
J 0
(-6490 4510);
DISPLAY 0.489362 (-6490 4510);
PAINT MONO (-6490 4510);
FORCEPROP 0 LASTPIN (-6500 4450) $PN P29
J 0
(-6490 4460);
DISPLAY 0.489362 (-6490 4460);
PAINT MONO (-6490 4460);
FORCEPROP 0 LASTPIN (-6500 4400) $PN P30
J 0
(-6490 4410);
DISPLAY 0.489362 (-6490 4410);
PAINT MONO (-6490 4410);
FORCEPROP 0 LASTPIN (-6500 4350) $PN P31
J 0
(-6490 4360);
DISPLAY 0.489362 (-6490 4360);
PAINT MONO (-6490 4360);
FORCEPROP 0 LASTPIN (-6500 4300) $PN P32
J 0
(-6490 4310);
DISPLAY 0.489362 (-6490 4310);
PAINT MONO (-6490 4310);
FORCEPROP 0 LASTPIN (-6500 4250) $PN P33
J 0
(-6490 4260);
DISPLAY 0.489362 (-6490 4260);
PAINT MONO (-6490 4260);
FORCEPROP 0 LASTPIN (-6500 4200) $PN P34
J 0
(-6490 4210);
DISPLAY 0.489362 (-6490 4210);
PAINT MONO (-6490 4210);
FORCEPROP 0 LASTPIN (-6500 4150) $PN P37
J 0
(-6490 4160);
DISPLAY 0.489362 (-6490 4160);
PAINT MONO (-6490 4160);
FORCEPROP 0 LASTPIN (-6500 4100) $PN P39
J 0
(-6490 4110);
DISPLAY 0.489362 (-6490 4110);
PAINT MONO (-6490 4110);
FORCEPROP 0 LASTPIN (-6500 4050) $PN P42
J 0
(-6490 4060);
DISPLAY 0.489362 (-6490 4060);
PAINT MONO (-6490 4060);
FORCEPROP 0 LASTPIN (-6500 4000) $PN P43
J 0
(-6490 4010);
DISPLAY 0.489362 (-6490 4010);
PAINT MONO (-6490 4010);
FORCEPROP 0 LASTPIN (-6500 3950) $PN P44
J 0
(-6490 3960);
DISPLAY 0.489362 (-6490 3960);
PAINT MONO (-6490 3960);
FORCEPROP 0 LASTPIN (-6500 3900) $PN P45
J 0
(-6490 3910);
DISPLAY 0.489362 (-6490 3910);
PAINT MONO (-6490 3910);
FORCEPROP 0 LASTPIN (-6500 3850) $PN P46
J 0
(-6490 3860);
DISPLAY 0.489362 (-6490 3860);
PAINT MONO (-6490 3860);
FORCEPROP 0 LASTPIN (-6500 3800) $PN P47
J 0
(-6490 3810);
DISPLAY 0.489362 (-6490 3810);
PAINT MONO (-6490 3810);
FORCEPROP 0 LASTPIN (-6500 3750) $PN P48
J 0
(-6490 3760);
DISPLAY 0.489362 (-6490 3760);
PAINT MONO (-6490 3760);
FORCEPROP 0 LASTPIN (-6500 3700) $PN P49
J 0
(-6490 3710);
DISPLAY 0.489362 (-6490 3710);
PAINT MONO (-6490 3710);
FORCEPROP 0 LASTPIN (-6500 3650) $PN P50
J 0
(-6490 3660);
DISPLAY 0.489362 (-6490 3660);
PAINT MONO (-6490 3660);
FORCEPROP 0 LASTPIN (-6500 3600) $PN P51
J 0
(-6490 3610);
DISPLAY 0.489362 (-6490 3610);
PAINT MONO (-6490 3610);
FORCEPROP 0 LASTPIN (-6500 3550) $PN P52
J 0
(-6490 3560);
DISPLAY 0.489362 (-6490 3560);
PAINT MONO (-6490 3560);
FORCEPROP 0 LASTPIN (-6500 3500) $PN P53
J 0
(-6490 3510);
DISPLAY 0.489362 (-6490 3510);
PAINT MONO (-6490 3510);
FORCEPROP 0 LASTPIN (-6500 3450) $PN P59
J 0
(-6490 3460);
DISPLAY 0.489362 (-6490 3460);
PAINT MONO (-6490 3460);
FORCEPROP 0 LASTPIN (-6500 3400) $PN P61
J 0
(-6490 3410);
DISPLAY 0.489362 (-6490 3410);
PAINT MONO (-6490 3410);
FORCEPROP 0 LASTPIN (-6500 3350) $PN P66
J 0
(-6490 3360);
DISPLAY 0.489362 (-6490 3360);
PAINT MONO (-6490 3360);
FORCEPROP 0 LASTPIN (-6500 3300) $PN P73
J 0
(-6490 3310);
DISPLAY 0.489362 (-6490 3310);
PAINT MONO (-6490 3310);
FORCEPROP 0 LASTPIN (-6500 3250) $PN R1
J 0
(-6490 3260);
DISPLAY 0.489362 (-6490 3260);
PAINT MONO (-6490 3260);
FORCEPROP 0 LASTPIN (-6500 3200) $PN R4
J 0
(-6490 3210);
DISPLAY 0.489362 (-6490 3210);
PAINT MONO (-6490 3210);
FORCEPROP 0 LASTPIN (-6500 3150) $PN R6
J 0
(-6490 3160);
DISPLAY 0.489362 (-6490 3160);
PAINT MONO (-6490 3160);
FORCEPROP 0 LASTPIN (-6500 3100) $PN R8
J 0
(-6490 3110);
DISPLAY 0.489362 (-6490 3110);
PAINT MONO (-6490 3110);
FORCEPROP 0 LASTPIN (-6500 3050) $PN R11
J 0
(-6490 3060);
DISPLAY 0.489362 (-6490 3060);
PAINT MONO (-6490 3060);
FORCEPROP 0 LASTPIN (-6500 3000) $PN R13
J 0
(-6490 3010);
DISPLAY 0.489362 (-6490 3010);
PAINT MONO (-6490 3010);
FORCEPROP 0 LASTPIN (-6500 2950) $PN R15
J 0
(-6490 2960);
DISPLAY 0.489362 (-6490 2960);
PAINT MONO (-6490 2960);
FORCEPROP 0 LASTPIN (-6500 2900) $PN R18
J 0
(-6490 2910);
DISPLAY 0.489362 (-6490 2910);
PAINT MONO (-6490 2910);
FORCEPROP 0 LASTPIN (-6500 2850) $PN R20
J 0
(-6490 2860);
DISPLAY 0.489362 (-6490 2860);
PAINT MONO (-6490 2860);
FORCEPROP 0 LASTPIN (-6500 2800) $PN R22
J 0
(-6490 2810);
DISPLAY 0.489362 (-6490 2810);
PAINT MONO (-6490 2810);
FORCEPROP 0 LASTPIN (-6500 2750) $PN R25
J 0
(-6490 2760);
DISPLAY 0.489362 (-6490 2760);
PAINT MONO (-6490 2760);
FORCEPROP 0 LASTPIN (-6500 2700) $PN R28
J 0
(-6490 2710);
DISPLAY 0.489362 (-6490 2710);
PAINT MONO (-6490 2710);
FORCEPROP 0 LASTPIN (-6500 2650) $PN R31
J 0
(-6490 2660);
DISPLAY 0.489362 (-6490 2660);
PAINT MONO (-6490 2660);
FORCEPROP 0 LASTPIN (-6500 2600) $PN R34
J 0
(-6490 2610);
DISPLAY 0.489362 (-6490 2610);
PAINT MONO (-6490 2610);
FORCEPROP 0 LASTPIN (-6500 2550) $PN R35
J 0
(-6490 2560);
DISPLAY 0.489362 (-6490 2560);
PAINT MONO (-6490 2560);
FORCEPROP 0 LASTPIN (-6500 2500) $PN R36
J 0
(-6490 2510);
DISPLAY 0.489362 (-6490 2510);
PAINT MONO (-6490 2510);
FORCEPROP 0 LASTPIN (-6500 2450) $PN R40
J 0
(-6490 2460);
DISPLAY 0.489362 (-6490 2460);
PAINT MONO (-6490 2460);
FORCEPROP 0 LASTPIN (-6500 2400) $PN R41
J 0
(-6490 2410);
DISPLAY 0.489362 (-6490 2410);
PAINT MONO (-6490 2410);
FORCEPROP 0 LASTPIN (-6500 2350) $PN R42
J 0
(-6490 2360);
DISPLAY 0.489362 (-6490 2360);
PAINT MONO (-6490 2360);
FORCEPROP 0 LASTPIN (-6500 2300) $PN R45
J 0
(-6490 2310);
DISPLAY 0.489362 (-6490 2310);
PAINT MONO (-6490 2310);
FORCEPROP 0 LASTPIN (-6500 2250) $PN R48
J 0
(-6490 2260);
DISPLAY 0.489362 (-6490 2260);
PAINT MONO (-6490 2260);
FORCEPROP 0 LASTPIN (-6500 2200) $PN R51
J 0
(-6490 2210);
DISPLAY 0.489362 (-6490 2210);
PAINT MONO (-6490 2210);
FORCEPROP 0 LASTPIN (-6500 2150) $PN R54
J 0
(-6490 2160);
DISPLAY 0.489362 (-6490 2160);
PAINT MONO (-6490 2160);
FORCEPROP 0 LASTPIN (-6500 2100) $PN R56
J 0
(-6490 2110);
DISPLAY 0.489362 (-6490 2110);
PAINT MONO (-6490 2110);
FORCEPROP 0 LASTPIN (-6500 2050) $PN R58
J 0
(-6490 2060);
DISPLAY 0.489362 (-6490 2060);
PAINT MONO (-6490 2060);
FORCEPROP 0 LASTPIN (-6500 2000) $PN R61
J 0
(-6490 2010);
DISPLAY 0.489362 (-6490 2010);
PAINT MONO (-6490 2010);
FORCEPROP 0 LASTPIN (-6500 1950) $PN R63
J 0
(-6490 1960);
DISPLAY 0.489362 (-6490 1960);
PAINT MONO (-6490 1960);
FORCEPROP 0 LASTPIN (-6500 1900) $PN R65
J 0
(-6490 1910);
DISPLAY 0.489362 (-6490 1910);
PAINT MONO (-6490 1910);
FORCEPROP 0 LASTPIN (-6500 1850) $PN R68
J 0
(-6490 1860);
DISPLAY 0.489362 (-6490 1860);
PAINT MONO (-6490 1860);
FORCEPROP 0 LASTPIN (-6500 1800) $PN R70
J 0
(-6490 1810);
DISPLAY 0.489362 (-6490 1810);
PAINT MONO (-6490 1810);
FORCEPROP 0 LASTPIN (-6500 1750) $PN R72
J 0
(-6490 1760);
DISPLAY 0.489362 (-6490 1760);
PAINT MONO (-6490 1760);
FORCEPROP 0 LASTPIN (-6500 1700) $PN R75
J 0
(-6490 1710);
DISPLAY 0.489362 (-6490 1710);
PAINT MONO (-6490 1710);
FORCEPROP 0 LASTPIN (-6500 1650) $PN T3
J 0
(-6490 1660);
DISPLAY 0.489362 (-6490 1660);
PAINT MONO (-6490 1660);
FORCEPROP 0 LASTPIN (-6500 1600) $PN T5
J 0
(-6490 1610);
DISPLAY 0.489362 (-6490 1610);
PAINT MONO (-6490 1610);
FORCEPROP 0 LASTPIN (-6500 1550) $PN T8
J 0
(-6490 1560);
DISPLAY 0.489362 (-6490 1560);
PAINT MONO (-6490 1560);
FORCEPROP 0 LASTPIN (-6500 1500) $PN T10
J 0
(-6490 1510);
DISPLAY 0.489362 (-6490 1510);
PAINT MONO (-6490 1510);
FORCEPROP 0 LASTPIN (-6500 1450) $PN T12
J 0
(-6490 1460);
DISPLAY 0.489362 (-6490 1460);
PAINT MONO (-6490 1460);
FORCEPROP 0 LASTPIN (-6500 1400) $PN T15
J 0
(-6490 1410);
DISPLAY 0.489362 (-6490 1410);
PAINT MONO (-6490 1410);
FORCEPROP 0 LASTPIN (-6500 1350) $PN T17
J 0
(-6490 1360);
DISPLAY 0.489362 (-6490 1360);
PAINT MONO (-6490 1360);
FORCEPROP 0 LASTPIN (-6500 1300) $PN T19
J 0
(-6490 1310);
DISPLAY 0.489362 (-6490 1310);
PAINT MONO (-6490 1310);
FORCEPROP 0 LASTPIN (-6500 1250) $PN T22
J 0
(-6490 1260);
DISPLAY 0.489362 (-6490 1260);
PAINT MONO (-6490 1260);
FORCEPROP 0 LASTPIN (-6500 1200) $PN T25
J 0
(-6490 1210);
DISPLAY 0.489362 (-6490 1210);
PAINT MONO (-6490 1210);
FORCEPROP 0 LASTPIN (-6500 1150) $PN T28
J 0
(-6490 1160);
DISPLAY 0.489362 (-6490 1160);
PAINT MONO (-6490 1160);
FORCEPROP 0 LASTPIN (-6500 1100) $PN T31
J 0
(-6490 1110);
DISPLAY 0.489362 (-6490 1110);
PAINT MONO (-6490 1110);
FORCEPROP 0 LASTPIN (-6500 1050) $PN T34
J 0
(-6490 1060);
DISPLAY 0.489362 (-6490 1060);
PAINT MONO (-6490 1060);
FORCEPROP 0 LASTPIN (-6500 1000) $PN T37
J 0
(-6490 1010);
DISPLAY 0.489362 (-6490 1010);
PAINT MONO (-6490 1010);
FORCEPROP 0 LASTPIN (-6500 950) $PN T39
J 0
(-6490 960);
DISPLAY 0.489362 (-6490 960);
PAINT MONO (-6490 960);
FORCEPROP 0 LASTPIN (-6500 900) $PN T42
J 0
(-6490 910);
DISPLAY 0.489362 (-6490 910);
PAINT MONO (-6490 910);
FORCEPROP 0 LASTPIN (-6500 850) $PN T45
J 0
(-6490 860);
DISPLAY 0.489362 (-6490 860);
PAINT MONO (-6490 860);
FORCEPROP 0 LASTPIN (-6500 800) $PN T48
J 0
(-6490 810);
DISPLAY 0.489362 (-6490 810);
PAINT MONO (-6490 810);
FORCEPROP 0 LASTPIN (-6500 750) $PN T51
J 0
(-6490 760);
DISPLAY 0.489362 (-6490 760);
PAINT MONO (-6490 760);
FORCEPROP 0 LASTPIN (-6500 700) $PN T54
J 0
(-6490 710);
DISPLAY 0.489362 (-6490 710);
PAINT MONO (-6490 710);
FORCEPROP 0 LASTPIN (-6500 650) $PN T57
J 0
(-6490 660);
DISPLAY 0.489362 (-6490 660);
PAINT MONO (-6490 660);
FORCEPROP 0 LASTPIN (-6500 600) $PN T59
J 0
(-6490 610);
DISPLAY 0.489362 (-6490 610);
PAINT MONO (-6490 610);
FORCEPROP 0 LASTPIN (-6500 550) $PN T61
J 0
(-6490 560);
DISPLAY 0.489362 (-6490 560);
PAINT MONO (-6490 560);
FORCEPROP 0 LASTPIN (-6500 500) $PN T64
J 0
(-6490 510);
DISPLAY 0.489362 (-6490 510);
PAINT MONO (-6490 510);
FORCEPROP 2 LAST PART_TYPE SMLF
J 0
(-7450 6700);
DISPLAY 1.021277 (-7450 6700);
FORCEPROP 1 LAST MATERIAL IO
J 0
(-7445 6532);
DISPLAY 0.489362 (-7445 6532);
PAINT SKYBLUE (-7445 6532);
FORCEPROP 2 LAST VALUE SOCKET6096_13568-001
J 0
(-7450 6575);
DISPLAY 0.489362 (-7450 6575);
PAINT SKYBLUE (-7450 6575);
FORCEPROP 2 LAST CDS_LIB pure_quanta
J 0
(-7050 3450);
DISPLAY INVISIBLE (-7050 3450);
FORCEPROP 1 LAST CDS_LMAN_SYM_OUTLINE -400,3050,400,-3050
J 0
(-7050 3450);
DISPLAY 0.468085 (-7050 3450);
PAINT GREEN (-7050 3450);
DISPLAY INVISIBLE (-7050 3450);
FORCEPROP 1 LAST NEEDS_NO_SIZE TRUE
J 0
(-7050 3450);
DISPLAY 0.723404 (-7050 3450);
PAINT GREEN (-7050 3450);
DISPLAY INVISIBLE (-7050 3450);
FORCEPROP 1 LAST PATH I15
J 0
(-7050 3450);
DISPLAY 0.723404 (-7050 3450);
PAINT GREEN (-7050 3450);
DISPLAY INVISIBLE (-7050 3450);
FORCEPROP 1 LAST PART_NUMBER DGA^6000030
J 0
(-7445 6659);
DISPLAY 0.489362 (-7445 6659);
PAINT SKYBLUE (-7445 6659);
DISPLAY INVISIBLE (-7445 6659);
FORCEADD UNIVERSAL_GND..1
(-9250 375);
FORCEPROP 3 LASTPIN (-9250 425) SIG_NAME GND\g
J 0
(-9240 435);
DISPLAY 0.659574 (-9240 435);
PAINT MONO (-9240 435);
DISPLAY INVISIBLE (-9240 435);
FORCEPROP 2 LAST CDS_LIB pure_quanta_power
J 0
(-9250 375);
DISPLAY INVISIBLE (-9250 375);
FORCEPROP 1 LAST HDL_POWER GND
J 1
(-9225 300);
DISPLAY 0.872340 (-9225 300);
PAINT GREEN (-9225 300);
DISPLAY INVISIBLE (-9225 300);
FORCEPROP 1 LAST PATH I18
J 0
(-9175 375);
DISPLAY 0.872340 (-9175 375);
PAINT AQUA (-9175 375);
DISPLAY INVISIBLE (-9175 375);
FORCEADD UNIVERSAL_GND..1
(-7900 400);
FORCEPROP 3 LASTPIN (-7900 450) SIG_NAME GND\g
J 0
(-7890 460);
DISPLAY 0.659574 (-7890 460);
PAINT MONO (-7890 460);
DISPLAY INVISIBLE (-7890 460);
FORCEPROP 2 LAST CDS_LIB pure_quanta_power
J 0
(-7900 400);
DISPLAY INVISIBLE (-7900 400);
FORCEPROP 1 LAST HDL_POWER GND
J 1
(-7875 325);
DISPLAY 0.872340 (-7875 325);
PAINT GREEN (-7875 325);
DISPLAY INVISIBLE (-7875 325);
FORCEPROP 1 LAST PATH I19
J 0
(-7825 400);
DISPLAY 0.872340 (-7825 400);
PAINT AQUA (-7825 400);
DISPLAY INVISIBLE (-7825 400);
FORCEADD UNIVERSAL_GND..1
(-7725 400);
FORCEPROP 3 LASTPIN (-7725 450) SIG_NAME GND\g
J 0
(-7715 460);
DISPLAY 0.659574 (-7715 460);
PAINT MONO (-7715 460);
DISPLAY INVISIBLE (-7715 460);
FORCEPROP 2 LAST CDS_LIB pure_quanta_power
J 0
(-7725 400);
DISPLAY INVISIBLE (-7725 400);
FORCEPROP 1 LAST HDL_POWER GND
J 1
(-7700 325);
DISPLAY 0.872340 (-7700 325);
PAINT GREEN (-7700 325);
DISPLAY INVISIBLE (-7700 325);
FORCEPROP 1 LAST PATH I20
J 0
(-7650 400);
DISPLAY 0.872340 (-7650 400);
PAINT AQUA (-7650 400);
DISPLAY INVISIBLE (-7650 400);
FORCEADD UNIVERSAL_GND..1
(-6375 425);
FORCEPROP 3 LASTPIN (-6375 475) SIG_NAME GND\g
J 0
(-6365 485);
DISPLAY 0.659574 (-6365 485);
PAINT MONO (-6365 485);
DISPLAY INVISIBLE (-6365 485);
FORCEPROP 2 LAST CDS_LIB pure_quanta_power
J 0
(-6375 425);
DISPLAY INVISIBLE (-6375 425);
FORCEPROP 1 LAST HDL_POWER GND
J 1
(-6350 350);
DISPLAY 0.872340 (-6350 350);
PAINT GREEN (-6350 350);
DISPLAY INVISIBLE (-6350 350);
FORCEPROP 1 LAST PATH I21
J 0
(-6300 425);
DISPLAY 0.872340 (-6300 425);
PAINT AQUA (-6300 425);
DISPLAY INVISIBLE (-6300 425);
FORCEADD UNIVERSAL_GND..1
(-6250 425);
FORCEPROP 3 LASTPIN (-6250 475) SIG_NAME GND\g
J 0
(-6240 485);
DISPLAY 0.659574 (-6240 485);
PAINT MONO (-6240 485);
DISPLAY INVISIBLE (-6240 485);
FORCEPROP 2 LAST CDS_LIB pure_quanta_power
J 0
(-6250 425);
DISPLAY INVISIBLE (-6250 425);
FORCEPROP 1 LAST HDL_POWER GND
J 1
(-6225 350);
DISPLAY 0.872340 (-6225 350);
PAINT GREEN (-6225 350);
DISPLAY INVISIBLE (-6225 350);
FORCEPROP 1 LAST PATH I22
J 0
(-6175 425);
DISPLAY 0.872340 (-6175 425);
PAINT AQUA (-6175 425);
DISPLAY INVISIBLE (-6175 425);
FORCEADD UNIVERSAL_GND..1
(-4900 500);
FORCEPROP 3 LASTPIN (-4900 550) SIG_NAME GND\g
J 0
(-4890 560);
DISPLAY 0.659574 (-4890 560);
PAINT MONO (-4890 560);
DISPLAY INVISIBLE (-4890 560);
FORCEPROP 2 LAST CDS_LIB pure_quanta_power
J 0
(-4900 500);
DISPLAY INVISIBLE (-4900 500);
FORCEPROP 1 LAST HDL_POWER GND
J 1
(-4875 425);
DISPLAY 0.872340 (-4875 425);
PAINT GREEN (-4875 425);
DISPLAY INVISIBLE (-4875 425);
FORCEPROP 1 LAST PATH I23
J 0
(-4825 500);
DISPLAY 0.872340 (-4825 500);
PAINT AQUA (-4825 500);
DISPLAY INVISIBLE (-4825 500);
FORCEADD UNIVERSAL_GND..1
(-4750 500);
FORCEPROP 3 LASTPIN (-4750 550) SIG_NAME GND\g
J 0
(-4740 560);
DISPLAY 0.659574 (-4740 560);
PAINT MONO (-4740 560);
DISPLAY INVISIBLE (-4740 560);
FORCEPROP 2 LAST CDS_LIB pure_quanta_power
J 0
(-4750 500);
DISPLAY INVISIBLE (-4750 500);
FORCEPROP 1 LAST HDL_POWER GND
J 1
(-4725 425);
DISPLAY 0.872340 (-4725 425);
PAINT GREEN (-4725 425);
DISPLAY INVISIBLE (-4725 425);
FORCEPROP 1 LAST PATH I24
J 0
(-4675 500);
DISPLAY 0.872340 (-4675 500);
PAINT AQUA (-4675 500);
DISPLAY INVISIBLE (-4675 500);
FORCEADD UNIVERSAL_GND..1
(-3400 525);
FORCEPROP 3 LASTPIN (-3400 575) SIG_NAME GND\g
J 0
(-3390 585);
DISPLAY 0.659574 (-3390 585);
PAINT MONO (-3390 585);
DISPLAY INVISIBLE (-3390 585);
FORCEPROP 2 LAST CDS_LIB pure_quanta_power
J 0
(-3400 525);
DISPLAY INVISIBLE (-3400 525);
FORCEPROP 1 LAST HDL_POWER GND
J 1
(-3375 450);
DISPLAY 0.872340 (-3375 450);
PAINT GREEN (-3375 450);
DISPLAY INVISIBLE (-3375 450);
FORCEPROP 1 LAST PATH I25
J 0
(-3325 525);
DISPLAY 0.872340 (-3325 525);
PAINT AQUA (-3325 525);
DISPLAY INVISIBLE (-3325 525);
FORCEADD UNIVERSAL_GND..1
(-3250 450);
FORCEPROP 3 LASTPIN (-3250 500) SIG_NAME GND\g
J 0
(-3240 510);
DISPLAY 0.659574 (-3240 510);
PAINT MONO (-3240 510);
DISPLAY INVISIBLE (-3240 510);
FORCEPROP 2 LAST CDS_LIB pure_quanta_power
J 0
(-3250 450);
DISPLAY INVISIBLE (-3250 450);
FORCEPROP 1 LAST HDL_POWER GND
J 1
(-3225 375);
DISPLAY 0.872340 (-3225 375);
PAINT GREEN (-3225 375);
DISPLAY INVISIBLE (-3225 375);
FORCEPROP 1 LAST PATH I26
J 0
(-3175 450);
DISPLAY 0.872340 (-3175 450);
PAINT AQUA (-3175 450);
DISPLAY INVISIBLE (-3175 450);
FORCEADD UNIVERSAL_GND..1
(-1925 475);
FORCEPROP 3 LASTPIN (-1925 525) SIG_NAME GND\g
J 0
(-1915 535);
DISPLAY 0.659574 (-1915 535);
PAINT MONO (-1915 535);
DISPLAY INVISIBLE (-1915 535);
FORCEPROP 2 LAST CDS_LIB pure_quanta_power
J 0
(-1925 475);
DISPLAY INVISIBLE (-1925 475);
FORCEPROP 1 LAST HDL_POWER GND
J 1
(-1900 400);
DISPLAY 0.872340 (-1900 400);
PAINT GREEN (-1900 400);
DISPLAY INVISIBLE (-1900 400);
FORCEPROP 1 LAST PATH I27
J 0
(-1850 475);
DISPLAY 0.872340 (-1850 475);
PAINT AQUA (-1850 475);
DISPLAY INVISIBLE (-1850 475);
FORCEADD UNIVERSAL_GND..1
(-1625 450);
FORCEPROP 3 LASTPIN (-1625 500) SIG_NAME GND\g
J 0
(-1615 510);
DISPLAY 0.659574 (-1615 510);
PAINT MONO (-1615 510);
DISPLAY INVISIBLE (-1615 510);
FORCEPROP 2 LAST CDS_LIB pure_quanta_power
J 0
(-1625 450);
DISPLAY INVISIBLE (-1625 450);
FORCEPROP 1 LAST HDL_POWER GND
J 1
(-1600 375);
DISPLAY 0.872340 (-1600 375);
PAINT GREEN (-1600 375);
DISPLAY INVISIBLE (-1600 375);
FORCEPROP 1 LAST PATH I28
J 0
(-1550 450);
DISPLAY 0.872340 (-1550 450);
PAINT AQUA (-1550 450);
DISPLAY INVISIBLE (-1550 450);
FORCEADD UNIVERSAL_GND..1
(-300 475);
FORCEPROP 3 LASTPIN (-300 525) SIG_NAME GND\g
J 0
(-290 535);
DISPLAY 0.659574 (-290 535);
PAINT MONO (-290 535);
DISPLAY INVISIBLE (-290 535);
FORCEPROP 2 LAST CDS_LIB pure_quanta_power
J 0
(-300 475);
DISPLAY INVISIBLE (-300 475);
FORCEPROP 1 LAST HDL_POWER GND
J 1
(-275 400);
DISPLAY 0.872340 (-275 400);
PAINT GREEN (-275 400);
DISPLAY INVISIBLE (-275 400);
FORCEPROP 1 LAST PATH I29
J 0
(-225 475);
DISPLAY 0.872340 (-225 475);
PAINT AQUA (-225 475);
DISPLAY INVISIBLE (-225 475);
FORCEADD GENOA_SP5..33
(-975 3500);
FORCEPROP 1 LAST LOCATION U26
J 0
(-1375 6650);
DISPLAY 0.489362 (-1375 6650);
PAINT SKYBLUE (-1375 6650);
FORCEPROP 0 LAST $SEC 33
J 0
(-1350 6900);
DISPLAY 0.680851 (-1350 6900);
PAINT MONO (-1350 6900);
DISPLAY INVISIBLE (-1350 6900);
FORCEPROP 0 LAST CDS_SEC 33
J 0
(-1350 6900);
DISPLAY 1.021277 (-1350 6900);
DISPLAY INVISIBLE (-1350 6900);
FORCEPROP 0 LASTPIN (-1525 6450) $PN AW63
J 2
(-1510 6460);
DISPLAY 0.489362 (-1510 6460);
PAINT MONO (-1510 6460);
FORCEPROP 0 LASTPIN (-1525 6400) $PN AW65
J 2
(-1510 6410);
DISPLAY 0.489362 (-1510 6410);
PAINT MONO (-1510 6410);
FORCEPROP 0 LASTPIN (-1525 6350) $PN AW68
J 2
(-1510 6360);
DISPLAY 0.489362 (-1510 6360);
PAINT MONO (-1510 6360);
FORCEPROP 0 LASTPIN (-1525 6300) $PN AW70
J 2
(-1510 6310);
DISPLAY 0.489362 (-1510 6310);
PAINT MONO (-1510 6310);
FORCEPROP 0 LASTPIN (-1525 6250) $PN AW72
J 2
(-1510 6260);
DISPLAY 0.489362 (-1510 6260);
PAINT MONO (-1510 6260);
FORCEPROP 0 LASTPIN (-1525 6200) $PN AW75
J 2
(-1510 6210);
DISPLAY 0.489362 (-1510 6210);
PAINT MONO (-1510 6210);
FORCEPROP 0 LASTPIN (-1525 6150) $PN AY3
J 2
(-1510 6160);
DISPLAY 0.489362 (-1510 6160);
PAINT MONO (-1510 6160);
FORCEPROP 0 LASTPIN (-1525 6100) $PN AY5
J 2
(-1510 6110);
DISPLAY 0.489362 (-1510 6110);
PAINT MONO (-1510 6110);
FORCEPROP 0 LASTPIN (-1525 6050) $PN AY8
J 2
(-1510 6060);
DISPLAY 0.489362 (-1510 6060);
PAINT MONO (-1510 6060);
FORCEPROP 0 LASTPIN (-1525 6000) $PN AY10
J 2
(-1510 6010);
DISPLAY 0.489362 (-1510 6010);
PAINT MONO (-1510 6010);
FORCEPROP 0 LASTPIN (-1525 5950) $PN AY12
J 2
(-1510 5960);
DISPLAY 0.489362 (-1510 5960);
PAINT MONO (-1510 5960);
FORCEPROP 0 LASTPIN (-1525 5900) $PN AY15
J 2
(-1510 5910);
DISPLAY 0.489362 (-1510 5910);
PAINT MONO (-1510 5910);
FORCEPROP 0 LASTPIN (-1525 5850) $PN AY17
J 2
(-1510 5860);
DISPLAY 0.489362 (-1510 5860);
PAINT MONO (-1510 5860);
FORCEPROP 0 LASTPIN (-1525 5800) $PN AY19
J 2
(-1510 5810);
DISPLAY 0.489362 (-1510 5810);
PAINT MONO (-1510 5810);
FORCEPROP 0 LASTPIN (-1525 5750) $PN AY23
J 2
(-1510 5760);
DISPLAY 0.489362 (-1510 5760);
PAINT MONO (-1510 5760);
FORCEPROP 0 LASTPIN (-1525 5700) $PN AY25
J 2
(-1510 5710);
DISPLAY 0.489362 (-1510 5710);
PAINT MONO (-1510 5710);
FORCEPROP 0 LASTPIN (-1525 5650) $PN AY27
J 2
(-1510 5660);
DISPLAY 0.489362 (-1510 5660);
PAINT MONO (-1510 5660);
FORCEPROP 0 LASTPIN (-1525 5600) $PN AY48
J 2
(-1510 5610);
DISPLAY 0.489362 (-1510 5610);
PAINT MONO (-1510 5610);
FORCEPROP 0 LASTPIN (-1525 5550) $PN AY50
J 2
(-1510 5560);
DISPLAY 0.489362 (-1510 5560);
PAINT MONO (-1510 5560);
FORCEPROP 0 LASTPIN (-1525 5500) $PN AY52
J 2
(-1510 5510);
DISPLAY 0.489362 (-1510 5510);
PAINT MONO (-1510 5510);
FORCEPROP 0 LASTPIN (-1525 5450) $PN AY54
J 2
(-1510 5460);
DISPLAY 0.489362 (-1510 5460);
PAINT MONO (-1510 5460);
FORCEPROP 0 LASTPIN (-1525 5400) $PN AY57
J 2
(-1510 5410);
DISPLAY 0.489362 (-1510 5410);
PAINT MONO (-1510 5410);
FORCEPROP 0 LASTPIN (-1525 5350) $PN AY59
J 2
(-1510 5360);
DISPLAY 0.489362 (-1510 5360);
PAINT MONO (-1510 5360);
FORCEPROP 0 LASTPIN (-1525 5300) $PN AY61
J 2
(-1510 5310);
DISPLAY 0.489362 (-1510 5310);
PAINT MONO (-1510 5310);
FORCEPROP 0 LASTPIN (-1525 5250) $PN AY64
J 2
(-1510 5260);
DISPLAY 0.489362 (-1510 5260);
PAINT MONO (-1510 5260);
FORCEPROP 0 LASTPIN (-1525 5200) $PN AY66
J 2
(-1510 5210);
DISPLAY 0.489362 (-1510 5210);
PAINT MONO (-1510 5210);
FORCEPROP 0 LASTPIN (-1525 5150) $PN AY68
J 2
(-1510 5160);
DISPLAY 0.489362 (-1510 5160);
PAINT MONO (-1510 5160);
FORCEPROP 0 LASTPIN (-1525 5100) $PN AY71
J 2
(-1510 5110);
DISPLAY 0.489362 (-1510 5110);
PAINT MONO (-1510 5110);
FORCEPROP 0 LASTPIN (-1525 5050) $PN AY73
J 2
(-1510 5060);
DISPLAY 0.489362 (-1510 5060);
PAINT MONO (-1510 5060);
FORCEPROP 0 LASTPIN (-1525 5000) $PN BA1
J 2
(-1510 5010);
DISPLAY 0.489362 (-1510 5010);
PAINT MONO (-1510 5010);
FORCEPROP 0 LASTPIN (-1525 4950) $PN BA6
J 2
(-1510 4960);
DISPLAY 0.489362 (-1510 4960);
PAINT MONO (-1510 4960);
FORCEPROP 0 LASTPIN (-1525 4900) $PN BA8
J 2
(-1510 4910);
DISPLAY 0.489362 (-1510 4910);
PAINT MONO (-1510 4910);
FORCEPROP 0 LASTPIN (-1525 4850) $PN BA13
J 2
(-1510 4860);
DISPLAY 0.489362 (-1510 4860);
PAINT MONO (-1510 4860);
FORCEPROP 0 LASTPIN (-1525 4800) $PN BA15
J 2
(-1510 4810);
DISPLAY 0.489362 (-1510 4810);
PAINT MONO (-1510 4810);
FORCEPROP 0 LASTPIN (-1525 4750) $PN BA20
J 2
(-1510 4760);
DISPLAY 0.489362 (-1510 4760);
PAINT MONO (-1510 4760);
FORCEPROP 0 LASTPIN (-1525 4700) $PN BA22
J 2
(-1510 4710);
DISPLAY 0.489362 (-1510 4710);
PAINT MONO (-1510 4710);
FORCEPROP 0 LASTPIN (-1525 4650) $PN BA24
J 2
(-1510 4660);
DISPLAY 0.489362 (-1510 4660);
PAINT MONO (-1510 4660);
FORCEPROP 0 LASTPIN (-1525 4600) $PN BA26
J 2
(-1510 4610);
DISPLAY 0.489362 (-1510 4610);
PAINT MONO (-1510 4610);
FORCEPROP 0 LASTPIN (-1525 4550) $PN BA28
J 2
(-1510 4560);
DISPLAY 0.489362 (-1510 4560);
PAINT MONO (-1510 4560);
FORCEPROP 0 LASTPIN (-1525 4500) $PN BA49
J 2
(-1510 4510);
DISPLAY 0.489362 (-1510 4510);
PAINT MONO (-1510 4510);
FORCEPROP 0 LASTPIN (-1525 4450) $PN BA51
J 2
(-1510 4460);
DISPLAY 0.489362 (-1510 4460);
PAINT MONO (-1510 4460);
FORCEPROP 0 LASTPIN (-1525 4400) $PN BA53
J 2
(-1510 4410);
DISPLAY 0.489362 (-1510 4410);
PAINT MONO (-1510 4410);
FORCEPROP 0 LASTPIN (-1525 4350) $PN BA56
J 2
(-1510 4360);
DISPLAY 0.489362 (-1510 4360);
PAINT MONO (-1510 4360);
FORCEPROP 0 LASTPIN (-1525 4300) $PN BA61
J 2
(-1510 4310);
DISPLAY 0.489362 (-1510 4310);
PAINT MONO (-1510 4310);
FORCEPROP 0 LASTPIN (-1525 4250) $PN BA63
J 2
(-1510 4260);
DISPLAY 0.489362 (-1510 4260);
PAINT MONO (-1510 4260);
FORCEPROP 0 LASTPIN (-1525 4200) $PN BA68
J 2
(-1510 4210);
DISPLAY 0.489362 (-1510 4210);
PAINT MONO (-1510 4210);
FORCEPROP 0 LASTPIN (-1525 4150) $PN BA70
J 2
(-1510 4160);
DISPLAY 0.489362 (-1510 4160);
PAINT MONO (-1510 4160);
FORCEPROP 0 LASTPIN (-1525 4100) $PN BA75
J 2
(-1510 4110);
DISPLAY 0.489362 (-1510 4110);
PAINT MONO (-1510 4110);
FORCEPROP 0 LASTPIN (-1525 4050) $PN BB3
J 2
(-1510 4060);
DISPLAY 0.489362 (-1510 4060);
PAINT MONO (-1510 4060);
FORCEPROP 0 LASTPIN (-1525 4000) $PN BB5
J 2
(-1510 4010);
DISPLAY 0.489362 (-1510 4010);
PAINT MONO (-1510 4010);
FORCEPROP 0 LASTPIN (-1525 3950) $PN BB8
J 2
(-1510 3960);
DISPLAY 0.489362 (-1510 3960);
PAINT MONO (-1510 3960);
FORCEPROP 0 LASTPIN (-1525 3900) $PN BB10
J 2
(-1510 3910);
DISPLAY 0.489362 (-1510 3910);
PAINT MONO (-1510 3910);
FORCEPROP 0 LASTPIN (-1525 3850) $PN BB12
J 2
(-1510 3860);
DISPLAY 0.489362 (-1510 3860);
PAINT MONO (-1510 3860);
FORCEPROP 0 LASTPIN (-1525 3800) $PN BB15
J 2
(-1510 3810);
DISPLAY 0.489362 (-1510 3810);
PAINT MONO (-1510 3810);
FORCEPROP 0 LASTPIN (-1525 3750) $PN BB17
J 2
(-1510 3760);
DISPLAY 0.489362 (-1510 3760);
PAINT MONO (-1510 3760);
FORCEPROP 0 LASTPIN (-1525 3700) $PN BB19
J 2
(-1510 3710);
DISPLAY 0.489362 (-1510 3710);
PAINT MONO (-1510 3710);
FORCEPROP 0 LASTPIN (-1525 3650) $PN BB23
J 2
(-1510 3660);
DISPLAY 0.489362 (-1510 3660);
PAINT MONO (-1510 3660);
FORCEPROP 0 LASTPIN (-1525 3600) $PN BB25
J 2
(-1510 3610);
DISPLAY 0.489362 (-1510 3610);
PAINT MONO (-1510 3610);
FORCEPROP 0 LASTPIN (-1525 3550) $PN BB27
J 2
(-1510 3560);
DISPLAY 0.489362 (-1510 3560);
PAINT MONO (-1510 3560);
FORCEPROP 0 LASTPIN (-1525 3500) $PN BB48
J 2
(-1510 3510);
DISPLAY 0.489362 (-1510 3510);
PAINT MONO (-1510 3510);
FORCEPROP 0 LASTPIN (-1525 3450) $PN BB50
J 2
(-1510 3460);
DISPLAY 0.489362 (-1510 3460);
PAINT MONO (-1510 3460);
FORCEPROP 0 LASTPIN (-1525 3400) $PN BB52
J 2
(-1510 3410);
DISPLAY 0.489362 (-1510 3410);
PAINT MONO (-1510 3410);
FORCEPROP 0 LASTPIN (-1525 3350) $PN BB54
J 2
(-1510 3360);
DISPLAY 0.489362 (-1510 3360);
PAINT MONO (-1510 3360);
FORCEPROP 0 LASTPIN (-1525 3300) $PN BB57
J 2
(-1510 3310);
DISPLAY 0.489362 (-1510 3310);
PAINT MONO (-1510 3310);
FORCEPROP 0 LASTPIN (-1525 3250) $PN BB59
J 2
(-1510 3260);
DISPLAY 0.489362 (-1510 3260);
PAINT MONO (-1510 3260);
FORCEPROP 0 LASTPIN (-1525 3200) $PN BB61
J 2
(-1510 3210);
DISPLAY 0.489362 (-1510 3210);
PAINT MONO (-1510 3210);
FORCEPROP 0 LASTPIN (-1525 3150) $PN BB64
J 2
(-1510 3160);
DISPLAY 0.489362 (-1510 3160);
PAINT MONO (-1510 3160);
FORCEPROP 0 LASTPIN (-1525 3100) $PN BB66
J 2
(-1510 3110);
DISPLAY 0.489362 (-1510 3110);
PAINT MONO (-1510 3110);
FORCEPROP 0 LASTPIN (-1525 3050) $PN BB68
J 2
(-1510 3060);
DISPLAY 0.489362 (-1510 3060);
PAINT MONO (-1510 3060);
FORCEPROP 0 LASTPIN (-1525 3000) $PN BB71
J 2
(-1510 3010);
DISPLAY 0.489362 (-1510 3010);
PAINT MONO (-1510 3010);
FORCEPROP 0 LASTPIN (-1525 2950) $PN BB73
J 2
(-1510 2960);
DISPLAY 0.489362 (-1510 2960);
PAINT MONO (-1510 2960);
FORCEPROP 0 LASTPIN (-1525 2900) $PN BC1
J 2
(-1510 2910);
DISPLAY 0.489362 (-1510 2910);
PAINT MONO (-1510 2910);
FORCEPROP 0 LASTPIN (-1525 2850) $PN BC4
J 2
(-1510 2860);
DISPLAY 0.489362 (-1510 2860);
PAINT MONO (-1510 2860);
FORCEPROP 0 LASTPIN (-1525 2800) $PN BC6
J 2
(-1510 2810);
DISPLAY 0.489362 (-1510 2810);
PAINT MONO (-1510 2810);
FORCEPROP 0 LASTPIN (-1525 2750) $PN BC8
J 2
(-1510 2760);
DISPLAY 0.489362 (-1510 2760);
PAINT MONO (-1510 2760);
FORCEPROP 0 LASTPIN (-1525 2700) $PN BC11
J 2
(-1510 2710);
DISPLAY 0.489362 (-1510 2710);
PAINT MONO (-1510 2710);
FORCEPROP 0 LASTPIN (-1525 2650) $PN BC13
J 2
(-1510 2660);
DISPLAY 0.489362 (-1510 2660);
PAINT MONO (-1510 2660);
FORCEPROP 0 LASTPIN (-1525 2600) $PN BC15
J 2
(-1510 2610);
DISPLAY 0.489362 (-1510 2610);
PAINT MONO (-1510 2610);
FORCEPROP 0 LASTPIN (-1525 2550) $PN BC18
J 2
(-1510 2560);
DISPLAY 0.489362 (-1510 2560);
PAINT MONO (-1510 2560);
FORCEPROP 0 LASTPIN (-1525 2500) $PN BC20
J 2
(-1510 2510);
DISPLAY 0.489362 (-1510 2510);
PAINT MONO (-1510 2510);
FORCEPROP 0 LASTPIN (-1525 2450) $PN BC22
J 2
(-1510 2460);
DISPLAY 0.489362 (-1510 2460);
PAINT MONO (-1510 2460);
FORCEPROP 0 LASTPIN (-1525 2400) $PN BC24
J 2
(-1510 2410);
DISPLAY 0.489362 (-1510 2410);
PAINT MONO (-1510 2410);
FORCEPROP 0 LASTPIN (-1525 2350) $PN BC26
J 2
(-1510 2360);
DISPLAY 0.489362 (-1510 2360);
PAINT MONO (-1510 2360);
FORCEPROP 0 LASTPIN (-1525 2300) $PN BC28
J 2
(-1510 2310);
DISPLAY 0.489362 (-1510 2310);
PAINT MONO (-1510 2310);
FORCEPROP 0 LASTPIN (-1525 2250) $PN BC49
J 2
(-1510 2260);
DISPLAY 0.489362 (-1510 2260);
PAINT MONO (-1510 2260);
FORCEPROP 0 LASTPIN (-1525 2200) $PN BC50
J 2
(-1510 2210);
DISPLAY 0.489362 (-1510 2210);
PAINT MONO (-1510 2210);
FORCEPROP 0 LASTPIN (-1525 2150) $PN BC51
J 2
(-1510 2160);
DISPLAY 0.489362 (-1510 2160);
PAINT MONO (-1510 2160);
FORCEPROP 0 LASTPIN (-1525 2100) $PN BC53
J 2
(-1510 2110);
DISPLAY 0.489362 (-1510 2110);
PAINT MONO (-1510 2110);
FORCEPROP 0 LASTPIN (-1525 2050) $PN BC56
J 2
(-1510 2060);
DISPLAY 0.489362 (-1510 2060);
PAINT MONO (-1510 2060);
FORCEPROP 0 LASTPIN (-1525 2000) $PN BC58
J 2
(-1510 2010);
DISPLAY 0.489362 (-1510 2010);
PAINT MONO (-1510 2010);
FORCEPROP 0 LASTPIN (-1525 1950) $PN BC61
J 2
(-1510 1960);
DISPLAY 0.489362 (-1510 1960);
PAINT MONO (-1510 1960);
FORCEPROP 0 LASTPIN (-1525 1900) $PN BC63
J 2
(-1510 1910);
DISPLAY 0.489362 (-1510 1910);
PAINT MONO (-1510 1910);
FORCEPROP 0 LASTPIN (-1525 1850) $PN BC65
J 2
(-1510 1860);
DISPLAY 0.489362 (-1510 1860);
PAINT MONO (-1510 1860);
FORCEPROP 0 LASTPIN (-1525 1800) $PN BC68
J 2
(-1510 1810);
DISPLAY 0.489362 (-1510 1810);
PAINT MONO (-1510 1810);
FORCEPROP 0 LASTPIN (-1525 1750) $PN BC70
J 2
(-1510 1760);
DISPLAY 0.489362 (-1510 1760);
PAINT MONO (-1510 1760);
FORCEPROP 0 LASTPIN (-1525 1700) $PN BC72
J 2
(-1510 1710);
DISPLAY 0.489362 (-1510 1710);
PAINT MONO (-1510 1710);
FORCEPROP 0 LASTPIN (-1525 1650) $PN BC75
J 2
(-1510 1660);
DISPLAY 0.489362 (-1510 1660);
PAINT MONO (-1510 1660);
FORCEPROP 0 LASTPIN (-1525 1600) $PN BD3
J 2
(-1510 1610);
DISPLAY 0.489362 (-1510 1610);
PAINT MONO (-1510 1610);
FORCEPROP 0 LASTPIN (-1525 1550) $PN BD8
J 2
(-1510 1560);
DISPLAY 0.489362 (-1510 1560);
PAINT MONO (-1510 1560);
FORCEPROP 0 LASTPIN (-1525 1500) $PN BD10
J 2
(-1510 1510);
DISPLAY 0.489362 (-1510 1510);
PAINT MONO (-1510 1510);
FORCEPROP 0 LASTPIN (-1525 1450) $PN BD15
J 2
(-1510 1460);
DISPLAY 0.489362 (-1510 1460);
PAINT MONO (-1510 1460);
FORCEPROP 0 LASTPIN (-1525 1400) $PN BD17
J 2
(-1510 1410);
DISPLAY 0.489362 (-1510 1410);
PAINT MONO (-1510 1410);
FORCEPROP 0 LASTPIN (-1525 1350) $PN BD23
J 2
(-1510 1360);
DISPLAY 0.489362 (-1510 1360);
PAINT MONO (-1510 1360);
FORCEPROP 0 LASTPIN (-1525 1300) $PN BD25
J 2
(-1510 1310);
DISPLAY 0.489362 (-1510 1310);
PAINT MONO (-1510 1310);
FORCEPROP 0 LASTPIN (-1525 1250) $PN BD27
J 2
(-1510 1260);
DISPLAY 0.489362 (-1510 1260);
PAINT MONO (-1510 1260);
FORCEPROP 0 LASTPIN (-1525 1200) $PN BD49
J 2
(-1510 1210);
DISPLAY 0.489362 (-1510 1210);
PAINT MONO (-1510 1210);
FORCEPROP 0 LASTPIN (-1525 1150) $PN BD51
J 2
(-1510 1160);
DISPLAY 0.489362 (-1510 1160);
PAINT MONO (-1510 1160);
FORCEPROP 0 LASTPIN (-1525 1100) $PN BD53
J 2
(-1510 1110);
DISPLAY 0.489362 (-1510 1110);
PAINT MONO (-1510 1110);
FORCEPROP 0 LASTPIN (-1525 1050) $PN BD57
J 2
(-1510 1060);
DISPLAY 0.489362 (-1510 1060);
PAINT MONO (-1510 1060);
FORCEPROP 0 LASTPIN (-1525 1000) $PN BD59
J 2
(-1510 1010);
DISPLAY 0.489362 (-1510 1010);
PAINT MONO (-1510 1010);
FORCEPROP 0 LASTPIN (-1525 950) $PN BD61
J 2
(-1510 960);
DISPLAY 0.489362 (-1510 960);
PAINT MONO (-1510 960);
FORCEPROP 0 LASTPIN (-1525 900) $PN BD64
J 2
(-1510 910);
DISPLAY 0.489362 (-1510 910);
PAINT MONO (-1510 910);
FORCEPROP 0 LASTPIN (-1525 850) $PN BD66
J 2
(-1510 860);
DISPLAY 0.489362 (-1510 860);
PAINT MONO (-1510 860);
FORCEPROP 0 LASTPIN (-1525 800) $PN BD68
J 2
(-1510 810);
DISPLAY 0.489362 (-1510 810);
PAINT MONO (-1510 810);
FORCEPROP 0 LASTPIN (-1525 750) $PN BD71
J 2
(-1510 760);
DISPLAY 0.489362 (-1510 760);
PAINT MONO (-1510 760);
FORCEPROP 0 LASTPIN (-1525 700) $PN BD73
J 2
(-1510 710);
DISPLAY 0.489362 (-1510 710);
PAINT MONO (-1510 710);
FORCEPROP 0 LASTPIN (-1525 650) $PN BF3
J 2
(-1510 660);
DISPLAY 0.489362 (-1510 660);
PAINT MONO (-1510 660);
FORCEPROP 0 LASTPIN (-1525 600) $PN BF5
J 2
(-1510 610);
DISPLAY 0.489362 (-1510 610);
PAINT MONO (-1510 610);
FORCEPROP 0 LASTPIN (-1525 550) $PN BF8
J 2
(-1510 560);
DISPLAY 0.489362 (-1510 560);
PAINT MONO (-1510 560);
FORCEPROP 0 LASTPIN (-425 6450) $PN BF10
J 0
(-460 6460);
DISPLAY 0.489362 (-460 6460);
PAINT MONO (-460 6460);
FORCEPROP 0 LASTPIN (-425 6400) $PN BF12
J 0
(-460 6410);
DISPLAY 0.489362 (-460 6410);
PAINT MONO (-460 6410);
FORCEPROP 0 LASTPIN (-425 6350) $PN BF15
J 0
(-460 6360);
DISPLAY 0.489362 (-460 6360);
PAINT MONO (-460 6360);
FORCEPROP 0 LASTPIN (-425 6300) $PN BF17
J 0
(-460 6310);
DISPLAY 0.489362 (-460 6310);
PAINT MONO (-460 6310);
FORCEPROP 0 LASTPIN (-425 6250) $PN BF19
J 0
(-460 6260);
DISPLAY 0.489362 (-460 6260);
PAINT MONO (-460 6260);
FORCEPROP 0 LASTPIN (-425 6200) $PN BF22
J 0
(-460 6210);
DISPLAY 0.489362 (-460 6210);
PAINT MONO (-460 6210);
FORCEPROP 0 LASTPIN (-425 6150) $PN BF24
J 0
(-460 6160);
DISPLAY 0.489362 (-460 6160);
PAINT MONO (-460 6160);
FORCEPROP 0 LASTPIN (-425 6100) $PN BF26
J 0
(-460 6110);
DISPLAY 0.489362 (-460 6110);
PAINT MONO (-460 6110);
FORCEPROP 0 LASTPIN (-425 6050) $PN BF28
J 0
(-460 6060);
DISPLAY 0.489362 (-460 6060);
PAINT MONO (-460 6060);
FORCEPROP 0 LASTPIN (-425 6000) $PN BF49
J 0
(-460 6010);
DISPLAY 0.489362 (-460 6010);
PAINT MONO (-460 6010);
FORCEPROP 0 LASTPIN (-425 5950) $PN BF50
J 0
(-460 5960);
DISPLAY 0.489362 (-460 5960);
PAINT MONO (-460 5960);
FORCEPROP 0 LASTPIN (-425 5900) $PN BF52
J 0
(-460 5910);
DISPLAY 0.489362 (-460 5910);
PAINT MONO (-460 5910);
FORCEPROP 0 LASTPIN (-425 5850) $PN BF54
J 0
(-460 5860);
DISPLAY 0.489362 (-460 5860);
PAINT MONO (-460 5860);
FORCEPROP 0 LASTPIN (-425 5800) $PN BF59
J 0
(-460 5810);
DISPLAY 0.489362 (-460 5810);
PAINT MONO (-460 5810);
FORCEPROP 0 LASTPIN (-425 5750) $PN BF61
J 0
(-460 5760);
DISPLAY 0.489362 (-460 5760);
PAINT MONO (-460 5760);
FORCEPROP 0 LASTPIN (-425 5700) $PN BF66
J 0
(-460 5710);
DISPLAY 0.489362 (-460 5710);
PAINT MONO (-460 5710);
FORCEPROP 0 LASTPIN (-425 5650) $PN BF68
J 0
(-460 5660);
DISPLAY 0.489362 (-460 5660);
PAINT MONO (-460 5660);
FORCEPROP 0 LASTPIN (-425 5600) $PN BF73
J 0
(-460 5610);
DISPLAY 0.489362 (-460 5610);
PAINT MONO (-460 5610);
FORCEPROP 0 LASTPIN (-425 5550) $PN BG1
J 0
(-460 5560);
DISPLAY 0.489362 (-460 5560);
PAINT MONO (-460 5560);
FORCEPROP 0 LASTPIN (-425 5500) $PN BG4
J 0
(-460 5510);
DISPLAY 0.489362 (-460 5510);
PAINT MONO (-460 5510);
FORCEPROP 0 LASTPIN (-425 5450) $PN BG6
J 0
(-460 5460);
DISPLAY 0.489362 (-460 5460);
PAINT MONO (-460 5460);
FORCEPROP 0 LASTPIN (-425 5400) $PN BG8
J 0
(-460 5410);
DISPLAY 0.489362 (-460 5410);
PAINT MONO (-460 5410);
FORCEPROP 0 LASTPIN (-425 5350) $PN BG11
J 0
(-460 5360);
DISPLAY 0.489362 (-460 5360);
PAINT MONO (-460 5360);
FORCEPROP 0 LASTPIN (-425 5300) $PN BG13
J 0
(-460 5310);
DISPLAY 0.489362 (-460 5310);
PAINT MONO (-460 5310);
FORCEPROP 0 LASTPIN (-425 5250) $PN BG15
J 0
(-460 5260);
DISPLAY 0.489362 (-460 5260);
PAINT MONO (-460 5260);
FORCEPROP 0 LASTPIN (-425 5200) $PN BG18
J 0
(-460 5210);
DISPLAY 0.489362 (-460 5210);
PAINT MONO (-460 5210);
FORCEPROP 0 LASTPIN (-425 5150) $PN BG20
J 0
(-460 5160);
DISPLAY 0.489362 (-460 5160);
PAINT MONO (-460 5160);
FORCEPROP 0 LASTPIN (-425 5100) $PN BG23
J 0
(-460 5110);
DISPLAY 0.489362 (-460 5110);
PAINT MONO (-460 5110);
FORCEPROP 0 LASTPIN (-425 5050) $PN BG25
J 0
(-460 5060);
DISPLAY 0.489362 (-460 5060);
PAINT MONO (-460 5060);
FORCEPROP 0 LASTPIN (-425 5000) $PN BG27
J 0
(-460 5010);
DISPLAY 0.489362 (-460 5010);
PAINT MONO (-460 5010);
FORCEPROP 0 LASTPIN (-425 4950) $PN BG49
J 0
(-460 4960);
DISPLAY 0.489362 (-460 4960);
PAINT MONO (-460 4960);
FORCEPROP 0 LASTPIN (-425 4900) $PN BG51
J 0
(-460 4910);
DISPLAY 0.489362 (-460 4910);
PAINT MONO (-460 4910);
FORCEPROP 0 LASTPIN (-425 4850) $PN BG53
J 0
(-460 4860);
DISPLAY 0.489362 (-460 4860);
PAINT MONO (-460 4860);
FORCEPROP 0 LASTPIN (-425 4800) $PN BG56
J 0
(-460 4810);
DISPLAY 0.489362 (-460 4810);
PAINT MONO (-460 4810);
FORCEPROP 0 LASTPIN (-425 4750) $PN BG58
J 0
(-460 4760);
DISPLAY 0.489362 (-460 4760);
PAINT MONO (-460 4760);
FORCEPROP 0 LASTPIN (-425 4700) $PN BG61
J 0
(-460 4710);
DISPLAY 0.489362 (-460 4710);
PAINT MONO (-460 4710);
FORCEPROP 0 LASTPIN (-425 4650) $PN BG63
J 0
(-460 4660);
DISPLAY 0.489362 (-460 4660);
PAINT MONO (-460 4660);
FORCEPROP 0 LASTPIN (-425 4600) $PN BG65
J 0
(-460 4610);
DISPLAY 0.489362 (-460 4610);
PAINT MONO (-460 4610);
FORCEPROP 0 LASTPIN (-425 4550) $PN BG68
J 0
(-460 4560);
DISPLAY 0.489362 (-460 4560);
PAINT MONO (-460 4560);
FORCEPROP 0 LASTPIN (-425 4500) $PN BG70
J 0
(-460 4510);
DISPLAY 0.489362 (-460 4510);
PAINT MONO (-460 4510);
FORCEPROP 0 LASTPIN (-425 4450) $PN BG72
J 0
(-460 4460);
DISPLAY 0.489362 (-460 4460);
PAINT MONO (-460 4460);
FORCEPROP 0 LASTPIN (-425 4400) $PN BG75
J 0
(-460 4410);
DISPLAY 0.489362 (-460 4410);
PAINT MONO (-460 4410);
FORCEPROP 0 LASTPIN (-425 4350) $PN BH3
J 0
(-460 4360);
DISPLAY 0.489362 (-460 4360);
PAINT MONO (-460 4360);
FORCEPROP 0 LASTPIN (-425 4300) $PN BH5
J 0
(-460 4310);
DISPLAY 0.489362 (-460 4310);
PAINT MONO (-460 4310);
FORCEPROP 0 LASTPIN (-425 4250) $PN BH8
J 0
(-460 4260);
DISPLAY 0.489362 (-460 4260);
PAINT MONO (-460 4260);
FORCEPROP 0 LASTPIN (-425 4200) $PN BH10
J 0
(-460 4210);
DISPLAY 0.489362 (-460 4210);
PAINT MONO (-460 4210);
FORCEPROP 0 LASTPIN (-425 4150) $PN BH12
J 0
(-460 4160);
DISPLAY 0.489362 (-460 4160);
PAINT MONO (-460 4160);
FORCEPROP 0 LASTPIN (-425 4100) $PN BH15
J 0
(-460 4110);
DISPLAY 0.489362 (-460 4110);
PAINT MONO (-460 4110);
FORCEPROP 0 LASTPIN (-425 4050) $PN BH17
J 0
(-460 4060);
DISPLAY 0.489362 (-460 4060);
PAINT MONO (-460 4060);
FORCEPROP 0 LASTPIN (-425 4000) $PN BH19
J 0
(-460 4010);
DISPLAY 0.489362 (-460 4010);
PAINT MONO (-460 4010);
FORCEPROP 0 LASTPIN (-425 3950) $PN BH22
J 0
(-460 3960);
DISPLAY 0.489362 (-460 3960);
PAINT MONO (-460 3960);
FORCEPROP 0 LASTPIN (-425 3900) $PN BH24
J 0
(-460 3910);
DISPLAY 0.489362 (-460 3910);
PAINT MONO (-460 3910);
FORCEPROP 0 LASTPIN (-425 3850) $PN BH26
J 0
(-460 3860);
DISPLAY 0.489362 (-460 3860);
PAINT MONO (-460 3860);
FORCEPROP 0 LASTPIN (-425 3800) $PN BH28
J 0
(-460 3810);
DISPLAY 0.489362 (-460 3810);
PAINT MONO (-460 3810);
FORCEPROP 0 LASTPIN (-425 3750) $PN BH49
J 0
(-460 3760);
DISPLAY 0.489362 (-460 3760);
PAINT MONO (-460 3760);
FORCEPROP 0 LASTPIN (-425 3700) $PN BH50
J 0
(-460 3710);
DISPLAY 0.489362 (-460 3710);
PAINT MONO (-460 3710);
FORCEPROP 0 LASTPIN (-425 3650) $PN BH52
J 0
(-460 3660);
DISPLAY 0.489362 (-460 3660);
PAINT MONO (-460 3660);
FORCEPROP 0 LASTPIN (-425 3600) $PN BH54
J 0
(-460 3610);
DISPLAY 0.489362 (-460 3610);
PAINT MONO (-460 3610);
FORCEPROP 0 LASTPIN (-425 3550) $PN BH57
J 0
(-460 3560);
DISPLAY 0.489362 (-460 3560);
PAINT MONO (-460 3560);
FORCEPROP 0 LASTPIN (-425 3500) $PN BH59
J 0
(-460 3510);
DISPLAY 0.489362 (-460 3510);
PAINT MONO (-460 3510);
FORCEPROP 0 LASTPIN (-425 3450) $PN BH61
J 0
(-460 3460);
DISPLAY 0.489362 (-460 3460);
PAINT MONO (-460 3460);
FORCEPROP 0 LASTPIN (-425 3400) $PN BH64
J 0
(-460 3410);
DISPLAY 0.489362 (-460 3410);
PAINT MONO (-460 3410);
FORCEPROP 0 LASTPIN (-425 3350) $PN BH66
J 0
(-460 3360);
DISPLAY 0.489362 (-460 3360);
PAINT MONO (-460 3360);
FORCEPROP 0 LASTPIN (-425 3300) $PN BH68
J 0
(-460 3310);
DISPLAY 0.489362 (-460 3310);
PAINT MONO (-460 3310);
FORCEPROP 0 LASTPIN (-425 3250) $PN BH71
J 0
(-460 3260);
DISPLAY 0.489362 (-460 3260);
PAINT MONO (-460 3260);
FORCEPROP 0 LASTPIN (-425 3200) $PN BH73
J 0
(-460 3210);
DISPLAY 0.489362 (-460 3210);
PAINT MONO (-460 3210);
FORCEPROP 0 LASTPIN (-425 3150) $PN BJ1
J 0
(-460 3160);
DISPLAY 0.489362 (-460 3160);
PAINT MONO (-460 3160);
FORCEPROP 0 LASTPIN (-425 3100) $PN BJ6
J 0
(-460 3110);
DISPLAY 0.489362 (-460 3110);
PAINT MONO (-460 3110);
FORCEPROP 0 LASTPIN (-425 3050) $PN BJ8
J 0
(-460 3060);
DISPLAY 0.489362 (-460 3060);
PAINT MONO (-460 3060);
FORCEPROP 0 LASTPIN (-425 3000) $PN BJ13
J 0
(-460 3010);
DISPLAY 0.489362 (-460 3010);
PAINT MONO (-460 3010);
FORCEPROP 0 LASTPIN (-425 2950) $PN BJ15
J 0
(-460 2960);
DISPLAY 0.489362 (-460 2960);
PAINT MONO (-460 2960);
FORCEPROP 0 LASTPIN (-425 2900) $PN BJ20
J 0
(-460 2910);
DISPLAY 0.489362 (-460 2910);
PAINT MONO (-460 2910);
FORCEPROP 0 LASTPIN (-425 2850) $PN BJ22
J 0
(-460 2860);
DISPLAY 0.489362 (-460 2860);
PAINT MONO (-460 2860);
FORCEPROP 0 LASTPIN (-425 2800) $PN BJ24
J 0
(-460 2810);
DISPLAY 0.489362 (-460 2810);
PAINT MONO (-460 2810);
FORCEPROP 0 LASTPIN (-425 2750) $PN BJ26
J 0
(-460 2760);
DISPLAY 0.489362 (-460 2760);
PAINT MONO (-460 2760);
FORCEPROP 0 LASTPIN (-425 2700) $PN BJ28
J 0
(-460 2710);
DISPLAY 0.489362 (-460 2710);
PAINT MONO (-460 2710);
FORCEPROP 0 LASTPIN (-425 2650) $PN BJ49
J 0
(-460 2660);
DISPLAY 0.489362 (-460 2660);
PAINT MONO (-460 2660);
FORCEPROP 0 LASTPIN (-425 2600) $PN BJ51
J 0
(-460 2610);
DISPLAY 0.489362 (-460 2610);
PAINT MONO (-460 2610);
FORCEPROP 0 LASTPIN (-425 2550) $PN BJ53
J 0
(-460 2560);
DISPLAY 0.489362 (-460 2560);
PAINT MONO (-460 2560);
FORCEPROP 0 LASTPIN (-425 2500) $PN BJ56
J 0
(-460 2510);
DISPLAY 0.489362 (-460 2510);
PAINT MONO (-460 2510);
FORCEPROP 0 LASTPIN (-425 2450) $PN BJ61
J 0
(-460 2460);
DISPLAY 0.489362 (-460 2460);
PAINT MONO (-460 2460);
FORCEPROP 0 LASTPIN (-425 2400) $PN BJ63
J 0
(-460 2410);
DISPLAY 0.489362 (-460 2410);
PAINT MONO (-460 2410);
FORCEPROP 0 LASTPIN (-425 2350) $PN BJ68
J 0
(-460 2360);
DISPLAY 0.489362 (-460 2360);
PAINT MONO (-460 2360);
FORCEPROP 0 LASTPIN (-425 2300) $PN BJ70
J 0
(-460 2310);
DISPLAY 0.489362 (-460 2310);
PAINT MONO (-460 2310);
FORCEPROP 0 LASTPIN (-425 2250) $PN BJ75
J 0
(-460 2260);
DISPLAY 0.489362 (-460 2260);
PAINT MONO (-460 2260);
FORCEPROP 0 LASTPIN (-425 2200) $PN BK3
J 0
(-460 2210);
DISPLAY 0.489362 (-460 2210);
PAINT MONO (-460 2210);
FORCEPROP 0 LASTPIN (-425 2150) $PN BK5
J 0
(-460 2160);
DISPLAY 0.489362 (-460 2160);
PAINT MONO (-460 2160);
FORCEPROP 0 LASTPIN (-425 2100) $PN BK8
J 0
(-460 2110);
DISPLAY 0.489362 (-460 2110);
PAINT MONO (-460 2110);
FORCEPROP 0 LASTPIN (-425 2050) $PN BK10
J 0
(-460 2060);
DISPLAY 0.489362 (-460 2060);
PAINT MONO (-460 2060);
FORCEPROP 0 LASTPIN (-425 2000) $PN BK12
J 0
(-460 2010);
DISPLAY 0.489362 (-460 2010);
PAINT MONO (-460 2010);
FORCEPROP 0 LASTPIN (-425 1950) $PN BK15
J 0
(-460 1960);
DISPLAY 0.489362 (-460 1960);
PAINT MONO (-460 1960);
FORCEPROP 0 LASTPIN (-425 1900) $PN BK17
J 0
(-460 1910);
DISPLAY 0.489362 (-460 1910);
PAINT MONO (-460 1910);
FORCEPROP 0 LASTPIN (-425 1850) $PN BK19
J 0
(-460 1860);
DISPLAY 0.489362 (-460 1860);
PAINT MONO (-460 1860);
FORCEPROP 0 LASTPIN (-425 1800) $PN BK23
J 0
(-460 1810);
DISPLAY 0.489362 (-460 1810);
PAINT MONO (-460 1810);
FORCEPROP 0 LASTPIN (-425 1750) $PN BK25
J 0
(-460 1760);
DISPLAY 0.489362 (-460 1760);
PAINT MONO (-460 1760);
FORCEPROP 0 LASTPIN (-425 1700) $PN BK27
J 0
(-460 1710);
DISPLAY 0.489362 (-460 1710);
PAINT MONO (-460 1710);
FORCEPROP 0 LASTPIN (-425 1650) $PN BK48
J 0
(-460 1660);
DISPLAY 0.489362 (-460 1660);
PAINT MONO (-460 1660);
FORCEPROP 0 LASTPIN (-425 1600) $PN BK50
J 0
(-460 1610);
DISPLAY 0.489362 (-460 1610);
PAINT MONO (-460 1610);
FORCEPROP 0 LASTPIN (-425 1550) $PN BK52
J 0
(-460 1560);
DISPLAY 0.489362 (-460 1560);
PAINT MONO (-460 1560);
FORCEPROP 0 LASTPIN (-425 1500) $PN BK54
J 0
(-460 1510);
DISPLAY 0.489362 (-460 1510);
PAINT MONO (-460 1510);
FORCEPROP 0 LASTPIN (-425 1450) $PN BK57
J 0
(-460 1460);
DISPLAY 0.489362 (-460 1460);
PAINT MONO (-460 1460);
FORCEPROP 0 LASTPIN (-425 1400) $PN BK59
J 0
(-460 1410);
DISPLAY 0.489362 (-460 1410);
PAINT MONO (-460 1410);
FORCEPROP 0 LASTPIN (-425 1350) $PN BK61
J 0
(-460 1360);
DISPLAY 0.489362 (-460 1360);
PAINT MONO (-460 1360);
FORCEPROP 0 LASTPIN (-425 1300) $PN BK64
J 0
(-460 1310);
DISPLAY 0.489362 (-460 1310);
PAINT MONO (-460 1310);
FORCEPROP 0 LASTPIN (-425 1250) $PN BK66
J 0
(-460 1260);
DISPLAY 0.489362 (-460 1260);
PAINT MONO (-460 1260);
FORCEPROP 0 LASTPIN (-425 1200) $PN BK68
J 0
(-460 1210);
DISPLAY 0.489362 (-460 1210);
PAINT MONO (-460 1210);
FORCEPROP 0 LASTPIN (-425 1150) $PN BK71
J 0
(-460 1160);
DISPLAY 0.489362 (-460 1160);
PAINT MONO (-460 1160);
FORCEPROP 0 LASTPIN (-425 1100) $PN BK73
J 0
(-460 1110);
DISPLAY 0.489362 (-460 1110);
PAINT MONO (-460 1110);
FORCEPROP 0 LASTPIN (-425 1050) $PN BL1
J 0
(-460 1060);
DISPLAY 0.489362 (-460 1060);
PAINT MONO (-460 1060);
FORCEPROP 0 LASTPIN (-425 1000) $PN BL4
J 0
(-460 1010);
DISPLAY 0.489362 (-460 1010);
PAINT MONO (-460 1010);
FORCEPROP 0 LASTPIN (-425 950) $PN BL6
J 0
(-460 960);
DISPLAY 0.489362 (-460 960);
PAINT MONO (-460 960);
FORCEPROP 0 LASTPIN (-425 900) $PN BL8
J 0
(-460 910);
DISPLAY 0.489362 (-460 910);
PAINT MONO (-460 910);
FORCEPROP 0 LASTPIN (-425 850) $PN BL11
J 0
(-460 860);
DISPLAY 0.489362 (-460 860);
PAINT MONO (-460 860);
FORCEPROP 0 LASTPIN (-425 800) $PN BL13
J 0
(-460 810);
DISPLAY 0.489362 (-460 810);
PAINT MONO (-460 810);
FORCEPROP 0 LASTPIN (-425 750) $PN BL15
J 0
(-460 760);
DISPLAY 0.489362 (-460 760);
PAINT MONO (-460 760);
FORCEPROP 0 LASTPIN (-425 700) $PN BL18
J 0
(-460 710);
DISPLAY 0.489362 (-460 710);
PAINT MONO (-460 710);
FORCEPROP 0 LASTPIN (-425 650) $PN BL20
J 0
(-460 660);
DISPLAY 0.489362 (-460 660);
PAINT MONO (-460 660);
FORCEPROP 0 LASTPIN (-425 600) $PN BL22
J 0
(-460 610);
DISPLAY 0.489362 (-460 610);
PAINT MONO (-460 610);
FORCEPROP 0 LASTPIN (-425 550) $PN BL24
J 0
(-460 560);
DISPLAY 0.489362 (-460 560);
PAINT MONO (-460 560);
FORCEPROP 2 LAST PART_TYPE SMLF
J 0
(-1600 6675);
DISPLAY 1.021277 (-1600 6675);
FORCEPROP 1 LAST MATERIAL IO
J 0
(-1370 6582);
DISPLAY 0.489362 (-1370 6582);
PAINT SKYBLUE (-1370 6582);
FORCEPROP 2 LAST VALUE SOCKET6096_13568-001
J 0
(-1375 6625);
DISPLAY 0.489362 (-1375 6625);
PAINT SKYBLUE (-1375 6625);
FORCEPROP 2 LAST CDS_LIB pure_quanta
J 0
(-975 3500);
DISPLAY INVISIBLE (-975 3500);
FORCEPROP 1 LAST CDS_LMAN_SYM_OUTLINE -400,3050,400,-3050
J 0
(-975 3500);
DISPLAY 0.468085 (-975 3500);
PAINT GREEN (-975 3500);
DISPLAY INVISIBLE (-975 3500);
FORCEPROP 1 LAST NEEDS_NO_SIZE TRUE
J 0
(-975 3500);
DISPLAY 0.723404 (-975 3500);
PAINT GREEN (-975 3500);
DISPLAY INVISIBLE (-975 3500);
FORCEPROP 1 LAST PATH I3
J 0
(-975 3500);
DISPLAY 0.723404 (-975 3500);
PAINT GREEN (-975 3500);
DISPLAY INVISIBLE (-975 3500);
FORCEPROP 1 LAST PART_NUMBER DGA^6000030
J 0
(-1375 6700);
DISPLAY 0.489362 (-1375 6700);
PAINT SKYBLUE (-1375 6700);
DISPLAY INVISIBLE (-1375 6700);
FORCEADD GENOA_SP5..32
(-2600 3500);
FORCEPROP 1 LAST LOCATION U26
J 0
(-3000 6650);
DISPLAY 0.489362 (-3000 6650);
PAINT SKYBLUE (-3000 6650);
FORCEPROP 0 LAST $SEC 32
J 0
(-2975 6900);
DISPLAY 0.680851 (-2975 6900);
PAINT MONO (-2975 6900);
DISPLAY INVISIBLE (-2975 6900);
FORCEPROP 0 LAST CDS_SEC 32
J 0
(-2975 6900);
DISPLAY 1.021277 (-2975 6900);
DISPLAY INVISIBLE (-2975 6900);
FORCEPROP 0 LASTPIN (-3150 6400) $PN AM42
J 2
(-3160 6410);
DISPLAY 0.489362 (-3160 6410);
PAINT MONO (-3160 6410);
FORCEPROP 0 LASTPIN (-3150 6350) $PN AM43
J 2
(-3160 6360);
DISPLAY 0.489362 (-3160 6360);
PAINT MONO (-3160 6360);
FORCEPROP 0 LASTPIN (-3150 6300) $PN AM44
J 2
(-3160 6310);
DISPLAY 0.489362 (-3160 6310);
PAINT MONO (-3160 6310);
FORCEPROP 0 LASTPIN (-3150 6250) $PN AM45
J 2
(-3160 6260);
DISPLAY 0.489362 (-3160 6260);
PAINT MONO (-3160 6260);
FORCEPROP 0 LASTPIN (-3150 6200) $PN AM46
J 2
(-3160 6210);
DISPLAY 0.489362 (-3160 6210);
PAINT MONO (-3160 6210);
FORCEPROP 0 LASTPIN (-3150 6150) $PN AM47
J 2
(-3160 6160);
DISPLAY 0.489362 (-3160 6160);
PAINT MONO (-3160 6160);
FORCEPROP 0 LASTPIN (-3150 6100) $PN AM48
J 2
(-3160 6110);
DISPLAY 0.489362 (-3160 6110);
PAINT MONO (-3160 6110);
FORCEPROP 0 LASTPIN (-3150 6050) $PN AM49
J 2
(-3160 6060);
DISPLAY 0.489362 (-3160 6060);
PAINT MONO (-3160 6060);
FORCEPROP 0 LASTPIN (-3150 6000) $PN AM50
J 2
(-3160 6010);
DISPLAY 0.489362 (-3160 6010);
PAINT MONO (-3160 6010);
FORCEPROP 0 LASTPIN (-3150 5950) $PN AM51
J 2
(-3160 5960);
DISPLAY 0.489362 (-3160 5960);
PAINT MONO (-3160 5960);
FORCEPROP 0 LASTPIN (-3150 5900) $PN AM52
J 2
(-3160 5910);
DISPLAY 0.489362 (-3160 5910);
PAINT MONO (-3160 5910);
FORCEPROP 0 LASTPIN (-3150 5850) $PN AM53
J 2
(-3160 5860);
DISPLAY 0.489362 (-3160 5860);
PAINT MONO (-3160 5860);
FORCEPROP 0 LASTPIN (-3150 5800) $PN AM59
J 2
(-3160 5810);
DISPLAY 0.489362 (-3160 5810);
PAINT MONO (-3160 5810);
FORCEPROP 0 LASTPIN (-3150 5750) $PN AM61
J 2
(-3160 5760);
DISPLAY 0.489362 (-3160 5760);
PAINT MONO (-3160 5760);
FORCEPROP 0 LASTPIN (-3150 5700) $PN AM66
J 2
(-3160 5710);
DISPLAY 0.489362 (-3160 5710);
PAINT MONO (-3160 5710);
FORCEPROP 0 LASTPIN (-3150 5650) $PN AM68
J 2
(-3160 5660);
DISPLAY 0.489362 (-3160 5660);
PAINT MONO (-3160 5660);
FORCEPROP 0 LASTPIN (-3150 5600) $PN AM73
J 2
(-3160 5610);
DISPLAY 0.489362 (-3160 5610);
PAINT MONO (-3160 5610);
FORCEPROP 0 LASTPIN (-3150 5550) $PN AN1
J 2
(-3160 5560);
DISPLAY 0.489362 (-3160 5560);
PAINT MONO (-3160 5560);
FORCEPROP 0 LASTPIN (-3150 5500) $PN AN4
J 2
(-3160 5510);
DISPLAY 0.489362 (-3160 5510);
PAINT MONO (-3160 5510);
FORCEPROP 0 LASTPIN (-3150 5450) $PN AN6
J 2
(-3160 5460);
DISPLAY 0.489362 (-3160 5460);
PAINT MONO (-3160 5460);
FORCEPROP 0 LASTPIN (-3150 5400) $PN AN8
J 2
(-3160 5410);
DISPLAY 0.489362 (-3160 5410);
PAINT MONO (-3160 5410);
FORCEPROP 0 LASTPIN (-3150 5350) $PN AN11
J 2
(-3160 5360);
DISPLAY 0.489362 (-3160 5360);
PAINT MONO (-3160 5360);
FORCEPROP 0 LASTPIN (-3150 5300) $PN AN13
J 2
(-3160 5310);
DISPLAY 0.489362 (-3160 5310);
PAINT MONO (-3160 5310);
FORCEPROP 0 LASTPIN (-3150 5250) $PN AN15
J 2
(-3160 5260);
DISPLAY 0.489362 (-3160 5260);
PAINT MONO (-3160 5260);
FORCEPROP 0 LASTPIN (-3150 5200) $PN AN18
J 2
(-3160 5210);
DISPLAY 0.489362 (-3160 5210);
PAINT MONO (-3160 5210);
FORCEPROP 0 LASTPIN (-3150 5150) $PN AN22
J 2
(-3160 5160);
DISPLAY 0.489362 (-3160 5160);
PAINT MONO (-3160 5160);
FORCEPROP 0 LASTPIN (-3150 5100) $PN AN25
J 2
(-3160 5110);
DISPLAY 0.489362 (-3160 5110);
PAINT MONO (-3160 5110);
FORCEPROP 0 LASTPIN (-3150 5050) $PN AN28
J 2
(-3160 5060);
DISPLAY 0.489362 (-3160 5060);
PAINT MONO (-3160 5060);
FORCEPROP 0 LASTPIN (-3150 5000) $PN AN31
J 2
(-3160 5010);
DISPLAY 0.489362 (-3160 5010);
PAINT MONO (-3160 5010);
FORCEPROP 0 LASTPIN (-3150 4950) $PN AN34
J 2
(-3160 4960);
DISPLAY 0.489362 (-3160 4960);
PAINT MONO (-3160 4960);
FORCEPROP 0 LASTPIN (-3150 4900) $PN AN35
J 2
(-3160 4910);
DISPLAY 0.489362 (-3160 4910);
PAINT MONO (-3160 4910);
FORCEPROP 0 LASTPIN (-3150 4850) $PN AN36
J 2
(-3160 4860);
DISPLAY 0.489362 (-3160 4860);
PAINT MONO (-3160 4860);
FORCEPROP 0 LASTPIN (-3150 4800) $PN AN40
J 2
(-3160 4810);
DISPLAY 0.489362 (-3160 4810);
PAINT MONO (-3160 4810);
FORCEPROP 0 LASTPIN (-3150 4750) $PN AN41
J 2
(-3160 4760);
DISPLAY 0.489362 (-3160 4760);
PAINT MONO (-3160 4760);
FORCEPROP 0 LASTPIN (-3150 4700) $PN AN42
J 2
(-3160 4710);
DISPLAY 0.489362 (-3160 4710);
PAINT MONO (-3160 4710);
FORCEPROP 0 LASTPIN (-3150 4650) $PN AN45
J 2
(-3160 4660);
DISPLAY 0.489362 (-3160 4660);
PAINT MONO (-3160 4660);
FORCEPROP 0 LASTPIN (-3150 4600) $PN AN48
J 2
(-3160 4610);
DISPLAY 0.489362 (-3160 4610);
PAINT MONO (-3160 4610);
FORCEPROP 0 LASTPIN (-3150 4550) $PN AN51
J 2
(-3160 4560);
DISPLAY 0.489362 (-3160 4560);
PAINT MONO (-3160 4560);
FORCEPROP 0 LASTPIN (-3150 4500) $PN AN54
J 2
(-3160 4510);
DISPLAY 0.489362 (-3160 4510);
PAINT MONO (-3160 4510);
FORCEPROP 0 LASTPIN (-3150 4450) $PN AN56
J 2
(-3160 4460);
DISPLAY 0.489362 (-3160 4460);
PAINT MONO (-3160 4460);
FORCEPROP 0 LASTPIN (-3150 4400) $PN AN58
J 2
(-3160 4410);
DISPLAY 0.489362 (-3160 4410);
PAINT MONO (-3160 4410);
FORCEPROP 0 LASTPIN (-3150 4350) $PN AN61
J 2
(-3160 4360);
DISPLAY 0.489362 (-3160 4360);
PAINT MONO (-3160 4360);
FORCEPROP 0 LASTPIN (-3150 4300) $PN AN63
J 2
(-3160 4310);
DISPLAY 0.489362 (-3160 4310);
PAINT MONO (-3160 4310);
FORCEPROP 0 LASTPIN (-3150 4250) $PN AN65
J 2
(-3160 4260);
DISPLAY 0.489362 (-3160 4260);
PAINT MONO (-3160 4260);
FORCEPROP 0 LASTPIN (-3150 4200) $PN AN68
J 2
(-3160 4210);
DISPLAY 0.489362 (-3160 4210);
PAINT MONO (-3160 4210);
FORCEPROP 0 LASTPIN (-3150 4150) $PN AN70
J 2
(-3160 4160);
DISPLAY 0.489362 (-3160 4160);
PAINT MONO (-3160 4160);
FORCEPROP 0 LASTPIN (-3150 4100) $PN AN72
J 2
(-3160 4110);
DISPLAY 0.489362 (-3160 4110);
PAINT MONO (-3160 4110);
FORCEPROP 0 LASTPIN (-3150 4050) $PN AN75
J 2
(-3160 4060);
DISPLAY 0.489362 (-3160 4060);
PAINT MONO (-3160 4060);
FORCEPROP 0 LASTPIN (-3150 4000) $PN AP3
J 2
(-3160 4010);
DISPLAY 0.489362 (-3160 4010);
PAINT MONO (-3160 4010);
FORCEPROP 0 LASTPIN (-3150 3950) $PN AP5
J 2
(-3160 3960);
DISPLAY 0.489362 (-3160 3960);
PAINT MONO (-3160 3960);
FORCEPROP 0 LASTPIN (-3150 3900) $PN AP8
J 2
(-3160 3910);
DISPLAY 0.489362 (-3160 3910);
PAINT MONO (-3160 3910);
FORCEPROP 0 LASTPIN (-3150 3850) $PN AP10
J 2
(-3160 3860);
DISPLAY 0.489362 (-3160 3860);
PAINT MONO (-3160 3860);
FORCEPROP 0 LASTPIN (-3150 3800) $PN AP12
J 2
(-3160 3810);
DISPLAY 0.489362 (-3160 3810);
PAINT MONO (-3160 3810);
FORCEPROP 0 LASTPIN (-3150 3750) $PN AP15
J 2
(-3160 3760);
DISPLAY 0.489362 (-3160 3760);
PAINT MONO (-3160 3760);
FORCEPROP 0 LASTPIN (-3150 3700) $PN AP17
J 2
(-3160 3710);
DISPLAY 0.489362 (-3160 3710);
PAINT MONO (-3160 3710);
FORCEPROP 0 LASTPIN (-3150 3650) $PN AP19
J 2
(-3160 3660);
DISPLAY 0.489362 (-3160 3660);
PAINT MONO (-3160 3660);
FORCEPROP 0 LASTPIN (-3150 3600) $PN AP22
J 2
(-3160 3610);
DISPLAY 0.489362 (-3160 3610);
PAINT MONO (-3160 3610);
FORCEPROP 0 LASTPIN (-3150 3550) $PN AP25
J 2
(-3160 3560);
DISPLAY 0.489362 (-3160 3560);
PAINT MONO (-3160 3560);
FORCEPROP 0 LASTPIN (-3150 3500) $PN AP28
J 2
(-3160 3510);
DISPLAY 0.489362 (-3160 3510);
PAINT MONO (-3160 3510);
FORCEPROP 0 LASTPIN (-3150 3450) $PN AP31
J 2
(-3160 3460);
DISPLAY 0.489362 (-3160 3460);
PAINT MONO (-3160 3460);
FORCEPROP 0 LASTPIN (-3150 3400) $PN AP34
J 2
(-3160 3410);
DISPLAY 0.489362 (-3160 3410);
PAINT MONO (-3160 3410);
FORCEPROP 0 LASTPIN (-3150 3350) $PN AP37
J 2
(-3160 3360);
DISPLAY 0.489362 (-3160 3360);
PAINT MONO (-3160 3360);
FORCEPROP 0 LASTPIN (-3150 3300) $PN AP39
J 2
(-3160 3310);
DISPLAY 0.489362 (-3160 3310);
PAINT MONO (-3160 3310);
FORCEPROP 0 LASTPIN (-3150 3250) $PN AP42
J 2
(-3160 3260);
DISPLAY 0.489362 (-3160 3260);
PAINT MONO (-3160 3260);
FORCEPROP 0 LASTPIN (-3150 3200) $PN AP45
J 2
(-3160 3210);
DISPLAY 0.489362 (-3160 3210);
PAINT MONO (-3160 3210);
FORCEPROP 0 LASTPIN (-3150 3150) $PN AP48
J 2
(-3160 3160);
DISPLAY 0.489362 (-3160 3160);
PAINT MONO (-3160 3160);
FORCEPROP 0 LASTPIN (-3150 3100) $PN AP51
J 2
(-3160 3110);
DISPLAY 0.489362 (-3160 3110);
PAINT MONO (-3160 3110);
FORCEPROP 0 LASTPIN (-3150 3050) $PN AP54
J 2
(-3160 3060);
DISPLAY 0.489362 (-3160 3060);
PAINT MONO (-3160 3060);
FORCEPROP 0 LASTPIN (-3150 3000) $PN AP57
J 2
(-3160 3010);
DISPLAY 0.489362 (-3160 3010);
PAINT MONO (-3160 3010);
FORCEPROP 0 LASTPIN (-3150 2950) $PN AP59
J 2
(-3160 2960);
DISPLAY 0.489362 (-3160 2960);
PAINT MONO (-3160 2960);
FORCEPROP 0 LASTPIN (-3150 2900) $PN AP61
J 2
(-3160 2910);
DISPLAY 0.489362 (-3160 2910);
PAINT MONO (-3160 2910);
FORCEPROP 0 LASTPIN (-3150 2850) $PN AP64
J 2
(-3160 2860);
DISPLAY 0.489362 (-3160 2860);
PAINT MONO (-3160 2860);
FORCEPROP 0 LASTPIN (-3150 2800) $PN AP66
J 2
(-3160 2810);
DISPLAY 0.489362 (-3160 2810);
PAINT MONO (-3160 2810);
FORCEPROP 0 LASTPIN (-3150 2750) $PN AP68
J 2
(-3160 2760);
DISPLAY 0.489362 (-3160 2760);
PAINT MONO (-3160 2760);
FORCEPROP 0 LASTPIN (-3150 2700) $PN AP71
J 2
(-3160 2710);
DISPLAY 0.489362 (-3160 2710);
PAINT MONO (-3160 2710);
FORCEPROP 0 LASTPIN (-3150 2650) $PN AP73
J 2
(-3160 2660);
DISPLAY 0.489362 (-3160 2660);
PAINT MONO (-3160 2660);
FORCEPROP 0 LASTPIN (-3150 2600) $PN AR1
J 2
(-3160 2610);
DISPLAY 0.489362 (-3160 2610);
PAINT MONO (-3160 2610);
FORCEPROP 0 LASTPIN (-3150 2550) $PN AR5
J 2
(-3160 2560);
DISPLAY 0.489362 (-3160 2560);
PAINT MONO (-3160 2560);
FORCEPROP 0 LASTPIN (-3150 2500) $PN AR6
J 2
(-3160 2510);
DISPLAY 0.489362 (-3160 2510);
PAINT MONO (-3160 2510);
FORCEPROP 0 LASTPIN (-3150 2450) $PN AR8
J 2
(-3160 2460);
DISPLAY 0.489362 (-3160 2460);
PAINT MONO (-3160 2460);
FORCEPROP 0 LASTPIN (-3150 2400) $PN AR9
J 2
(-3160 2410);
DISPLAY 0.489362 (-3160 2410);
PAINT MONO (-3160 2410);
FORCEPROP 0 LASTPIN (-3150 2350) $PN AR12
J 2
(-3160 2360);
DISPLAY 0.489362 (-3160 2360);
PAINT MONO (-3160 2360);
FORCEPROP 0 LASTPIN (-3150 2300) $PN AR13
J 2
(-3160 2310);
DISPLAY 0.489362 (-3160 2310);
PAINT MONO (-3160 2310);
FORCEPROP 0 LASTPIN (-3150 2250) $PN AR15
J 2
(-3160 2260);
DISPLAY 0.489362 (-3160 2260);
PAINT MONO (-3160 2260);
FORCEPROP 0 LASTPIN (-3150 2200) $PN AR16
J 2
(-3160 2210);
DISPLAY 0.489362 (-3160 2210);
PAINT MONO (-3160 2210);
FORCEPROP 0 LASTPIN (-3150 2150) $PN AR19
J 2
(-3160 2160);
DISPLAY 0.489362 (-3160 2160);
PAINT MONO (-3160 2160);
FORCEPROP 0 LASTPIN (-3150 2100) $PN AR20
J 2
(-3160 2110);
DISPLAY 0.489362 (-3160 2110);
PAINT MONO (-3160 2110);
FORCEPROP 0 LASTPIN (-3150 2050) $PN AR22
J 2
(-3160 2060);
DISPLAY 0.489362 (-3160 2060);
PAINT MONO (-3160 2060);
FORCEPROP 0 LASTPIN (-3150 2000) $PN AR24
J 2
(-3160 2010);
DISPLAY 0.489362 (-3160 2010);
PAINT MONO (-3160 2010);
FORCEPROP 0 LASTPIN (-3150 1950) $PN AR26
J 2
(-3160 1960);
DISPLAY 0.489362 (-3160 1960);
PAINT MONO (-3160 1960);
FORCEPROP 0 LASTPIN (-3150 1900) $PN AR28
J 2
(-3160 1910);
DISPLAY 0.489362 (-3160 1910);
PAINT MONO (-3160 1910);
FORCEPROP 0 LASTPIN (-3150 1850) $PN AR30
J 2
(-3160 1860);
DISPLAY 0.489362 (-3160 1860);
PAINT MONO (-3160 1860);
FORCEPROP 0 LASTPIN (-3150 1800) $PN AR32
J 2
(-3160 1810);
DISPLAY 0.489362 (-3160 1810);
PAINT MONO (-3160 1810);
FORCEPROP 0 LASTPIN (-3150 1750) $PN AR34
J 2
(-3160 1760);
DISPLAY 0.489362 (-3160 1760);
PAINT MONO (-3160 1760);
FORCEPROP 0 LASTPIN (-3150 1700) $PN AR36
J 2
(-3160 1710);
DISPLAY 0.489362 (-3160 1710);
PAINT MONO (-3160 1710);
FORCEPROP 0 LASTPIN (-3150 1650) $PN AR41
J 2
(-3160 1660);
DISPLAY 0.489362 (-3160 1660);
PAINT MONO (-3160 1660);
FORCEPROP 0 LASTPIN (-3150 1600) $PN AR43
J 2
(-3160 1610);
DISPLAY 0.489362 (-3160 1610);
PAINT MONO (-3160 1610);
FORCEPROP 0 LASTPIN (-3150 1550) $PN AR45
J 2
(-3160 1560);
DISPLAY 0.489362 (-3160 1560);
PAINT MONO (-3160 1560);
FORCEPROP 0 LASTPIN (-3150 1500) $PN AR47
J 2
(-3160 1510);
DISPLAY 0.489362 (-3160 1510);
PAINT MONO (-3160 1510);
FORCEPROP 0 LASTPIN (-3150 1450) $PN AR49
J 2
(-3160 1460);
DISPLAY 0.489362 (-3160 1460);
PAINT MONO (-3160 1460);
FORCEPROP 0 LASTPIN (-3150 1400) $PN AR51
J 2
(-3160 1410);
DISPLAY 0.489362 (-3160 1410);
PAINT MONO (-3160 1410);
FORCEPROP 0 LASTPIN (-3150 1350) $PN AR53
J 2
(-3160 1360);
DISPLAY 0.489362 (-3160 1360);
PAINT MONO (-3160 1360);
FORCEPROP 0 LASTPIN (-3150 1300) $PN AR56
J 2
(-3160 1310);
DISPLAY 0.489362 (-3160 1310);
PAINT MONO (-3160 1310);
FORCEPROP 0 LASTPIN (-3150 1250) $PN AR57
J 2
(-3160 1260);
DISPLAY 0.489362 (-3160 1260);
PAINT MONO (-3160 1260);
FORCEPROP 0 LASTPIN (-3150 1200) $PN AR60
J 2
(-3160 1210);
DISPLAY 0.489362 (-3160 1210);
PAINT MONO (-3160 1210);
FORCEPROP 0 LASTPIN (-3150 1150) $PN AR61
J 2
(-3160 1160);
DISPLAY 0.489362 (-3160 1160);
PAINT MONO (-3160 1160);
FORCEPROP 0 LASTPIN (-3150 1100) $PN AR63
J 2
(-3160 1110);
DISPLAY 0.489362 (-3160 1110);
PAINT MONO (-3160 1110);
FORCEPROP 0 LASTPIN (-3150 1050) $PN AR64
J 2
(-3160 1060);
DISPLAY 0.489362 (-3160 1060);
PAINT MONO (-3160 1060);
FORCEPROP 0 LASTPIN (-3150 1000) $PN AR67
J 2
(-3160 1010);
DISPLAY 0.489362 (-3160 1010);
PAINT MONO (-3160 1010);
FORCEPROP 0 LASTPIN (-3150 950) $PN AR68
J 2
(-3160 960);
DISPLAY 0.489362 (-3160 960);
PAINT MONO (-3160 960);
FORCEPROP 0 LASTPIN (-3150 900) $PN AR70
J 2
(-3160 910);
DISPLAY 0.489362 (-3160 910);
PAINT MONO (-3160 910);
FORCEPROP 0 LASTPIN (-3150 850) $PN AR71
J 2
(-3160 860);
DISPLAY 0.489362 (-3160 860);
PAINT MONO (-3160 860);
FORCEPROP 0 LASTPIN (-3150 800) $PN AR75
J 2
(-3160 810);
DISPLAY 0.489362 (-3160 810);
PAINT MONO (-3160 810);
FORCEPROP 0 LASTPIN (-3150 750) $PN AT3
J 2
(-3160 760);
DISPLAY 0.489362 (-3160 760);
PAINT MONO (-3160 760);
FORCEPROP 0 LASTPIN (-3150 700) $PN AT4
J 2
(-3160 710);
DISPLAY 0.489362 (-3160 710);
PAINT MONO (-3160 710);
FORCEPROP 0 LASTPIN (-3150 650) $PN AT5
J 2
(-3160 660);
DISPLAY 0.489362 (-3160 660);
PAINT MONO (-3160 660);
FORCEPROP 0 LASTPIN (-3150 600) $PN AT6
J 2
(-3160 610);
DISPLAY 0.489362 (-3160 610);
PAINT MONO (-3160 610);
FORCEPROP 0 LASTPIN (-3150 550) $PN AT8
J 2
(-3160 560);
DISPLAY 0.489362 (-3160 560);
PAINT MONO (-3160 560);
FORCEPROP 0 LASTPIN (-2050 6450) $PN AT9
J 0
(-2085 6460);
DISPLAY 0.489362 (-2085 6460);
PAINT MONO (-2085 6460);
FORCEPROP 0 LASTPIN (-2050 6400) $PN AT10
J 0
(-2085 6410);
DISPLAY 0.489362 (-2085 6410);
PAINT MONO (-2085 6410);
FORCEPROP 0 LASTPIN (-2050 6350) $PN AT12
J 0
(-2085 6360);
DISPLAY 0.489362 (-2085 6360);
PAINT MONO (-2085 6360);
FORCEPROP 0 LASTPIN (-2050 6300) $PN AT13
J 0
(-2085 6310);
DISPLAY 0.489362 (-2085 6310);
PAINT MONO (-2085 6310);
FORCEPROP 0 LASTPIN (-2050 6250) $PN AT15
J 0
(-2085 6260);
DISPLAY 0.489362 (-2085 6260);
PAINT MONO (-2085 6260);
FORCEPROP 0 LASTPIN (-2050 6200) $PN AT16
J 0
(-2085 6210);
DISPLAY 0.489362 (-2085 6210);
PAINT MONO (-2085 6210);
FORCEPROP 0 LASTPIN (-2050 6150) $PN AT17
J 0
(-2085 6160);
DISPLAY 0.489362 (-2085 6160);
PAINT MONO (-2085 6160);
FORCEPROP 0 LASTPIN (-2050 6100) $PN AT19
J 0
(-2085 6110);
DISPLAY 0.489362 (-2085 6110);
PAINT MONO (-2085 6110);
FORCEPROP 0 LASTPIN (-2050 6050) $PN AT20
J 0
(-2085 6060);
DISPLAY 0.489362 (-2085 6060);
PAINT MONO (-2085 6060);
FORCEPROP 0 LASTPIN (-2050 6000) $PN AT23
J 0
(-2085 6010);
DISPLAY 0.489362 (-2085 6010);
PAINT MONO (-2085 6010);
FORCEPROP 0 LASTPIN (-2050 5950) $PN AT25
J 0
(-2085 5960);
DISPLAY 0.489362 (-2085 5960);
PAINT MONO (-2085 5960);
FORCEPROP 0 LASTPIN (-2050 5900) $PN AT27
J 0
(-2085 5910);
DISPLAY 0.489362 (-2085 5910);
PAINT MONO (-2085 5910);
FORCEPROP 0 LASTPIN (-2050 5850) $PN AT29
J 0
(-2085 5860);
DISPLAY 0.489362 (-2085 5860);
PAINT MONO (-2085 5860);
FORCEPROP 0 LASTPIN (-2050 5800) $PN AT31
J 0
(-2085 5810);
DISPLAY 0.489362 (-2085 5810);
PAINT MONO (-2085 5810);
FORCEPROP 0 LASTPIN (-2050 5750) $PN AT33
J 0
(-2085 5760);
DISPLAY 0.489362 (-2085 5760);
PAINT MONO (-2085 5760);
FORCEPROP 0 LASTPIN (-2050 5700) $PN AT35
J 0
(-2085 5710);
DISPLAY 0.489362 (-2085 5710);
PAINT MONO (-2085 5710);
FORCEPROP 0 LASTPIN (-2050 5650) $PN AT37
J 0
(-2085 5660);
DISPLAY 0.489362 (-2085 5660);
PAINT MONO (-2085 5660);
FORCEPROP 0 LASTPIN (-2050 5600) $PN AT40
J 0
(-2085 5610);
DISPLAY 0.489362 (-2085 5610);
PAINT MONO (-2085 5610);
FORCEPROP 0 LASTPIN (-2050 5550) $PN AT42
J 0
(-2085 5560);
DISPLAY 0.489362 (-2085 5560);
PAINT MONO (-2085 5560);
FORCEPROP 0 LASTPIN (-2050 5500) $PN AT44
J 0
(-2085 5510);
DISPLAY 0.489362 (-2085 5510);
PAINT MONO (-2085 5510);
FORCEPROP 0 LASTPIN (-2050 5450) $PN AT46
J 0
(-2085 5460);
DISPLAY 0.489362 (-2085 5460);
PAINT MONO (-2085 5460);
FORCEPROP 0 LASTPIN (-2050 5400) $PN AT48
J 0
(-2085 5410);
DISPLAY 0.489362 (-2085 5410);
PAINT MONO (-2085 5410);
FORCEPROP 0 LASTPIN (-2050 5350) $PN AT50
J 0
(-2085 5360);
DISPLAY 0.489362 (-2085 5360);
PAINT MONO (-2085 5360);
FORCEPROP 0 LASTPIN (-2050 5300) $PN AT52
J 0
(-2085 5310);
DISPLAY 0.489362 (-2085 5310);
PAINT MONO (-2085 5310);
FORCEPROP 0 LASTPIN (-2050 5250) $PN AT54
J 0
(-2085 5260);
DISPLAY 0.489362 (-2085 5260);
PAINT MONO (-2085 5260);
FORCEPROP 0 LASTPIN (-2050 5200) $PN AT56
J 0
(-2085 5210);
DISPLAY 0.489362 (-2085 5210);
PAINT MONO (-2085 5210);
FORCEPROP 0 LASTPIN (-2050 5150) $PN AT57
J 0
(-2085 5160);
DISPLAY 0.489362 (-2085 5160);
PAINT MONO (-2085 5160);
FORCEPROP 0 LASTPIN (-2050 5100) $PN AT59
J 0
(-2085 5110);
DISPLAY 0.489362 (-2085 5110);
PAINT MONO (-2085 5110);
FORCEPROP 0 LASTPIN (-2050 5050) $PN AT60
J 0
(-2085 5060);
DISPLAY 0.489362 (-2085 5060);
PAINT MONO (-2085 5060);
FORCEPROP 0 LASTPIN (-2050 5000) $PN AT61
J 0
(-2085 5010);
DISPLAY 0.489362 (-2085 5010);
PAINT MONO (-2085 5010);
FORCEPROP 0 LASTPIN (-2050 4950) $PN AT63
J 0
(-2085 4960);
DISPLAY 0.489362 (-2085 4960);
PAINT MONO (-2085 4960);
FORCEPROP 0 LASTPIN (-2050 4900) $PN AT64
J 0
(-2085 4910);
DISPLAY 0.489362 (-2085 4910);
PAINT MONO (-2085 4910);
FORCEPROP 0 LASTPIN (-2050 4850) $PN AT66
J 0
(-2085 4860);
DISPLAY 0.489362 (-2085 4860);
PAINT MONO (-2085 4860);
FORCEPROP 0 LASTPIN (-2050 4800) $PN AT67
J 0
(-2085 4810);
DISPLAY 0.489362 (-2085 4810);
PAINT MONO (-2085 4810);
FORCEPROP 0 LASTPIN (-2050 4750) $PN AT68
J 0
(-2085 4760);
DISPLAY 0.489362 (-2085 4760);
PAINT MONO (-2085 4760);
FORCEPROP 0 LASTPIN (-2050 4700) $PN AT70
J 0
(-2085 4710);
DISPLAY 0.489362 (-2085 4710);
PAINT MONO (-2085 4710);
FORCEPROP 0 LASTPIN (-2050 4650) $PN AT71
J 0
(-2085 4660);
DISPLAY 0.489362 (-2085 4660);
PAINT MONO (-2085 4660);
FORCEPROP 0 LASTPIN (-2050 4600) $PN AT72
J 0
(-2085 4610);
DISPLAY 0.489362 (-2085 4610);
PAINT MONO (-2085 4610);
FORCEPROP 0 LASTPIN (-2050 4550) $PN AT73
J 0
(-2085 4560);
DISPLAY 0.489362 (-2085 4560);
PAINT MONO (-2085 4560);
FORCEPROP 0 LASTPIN (-2050 4500) $PN AU1
J 0
(-2085 4510);
DISPLAY 0.489362 (-2085 4510);
PAINT MONO (-2085 4510);
FORCEPROP 0 LASTPIN (-2050 4450) $PN AU3
J 0
(-2085 4460);
DISPLAY 0.489362 (-2085 4460);
PAINT MONO (-2085 4460);
FORCEPROP 0 LASTPIN (-2050 4400) $PN AU4
J 0
(-2085 4410);
DISPLAY 0.489362 (-2085 4410);
PAINT MONO (-2085 4410);
FORCEPROP 0 LASTPIN (-2050 4350) $PN AU6
J 0
(-2085 4360);
DISPLAY 0.489362 (-2085 4360);
PAINT MONO (-2085 4360);
FORCEPROP 0 LASTPIN (-2050 4300) $PN AU8
J 0
(-2085 4310);
DISPLAY 0.489362 (-2085 4310);
PAINT MONO (-2085 4310);
FORCEPROP 0 LASTPIN (-2050 4250) $PN AU11
J 0
(-2085 4260);
DISPLAY 0.489362 (-2085 4260);
PAINT MONO (-2085 4260);
FORCEPROP 0 LASTPIN (-2050 4200) $PN AU13
J 0
(-2085 4210);
DISPLAY 0.489362 (-2085 4210);
PAINT MONO (-2085 4210);
FORCEPROP 0 LASTPIN (-2050 4150) $PN AU15
J 0
(-2085 4160);
DISPLAY 0.489362 (-2085 4160);
PAINT MONO (-2085 4160);
FORCEPROP 0 LASTPIN (-2050 4100) $PN AU18
J 0
(-2085 4110);
DISPLAY 0.489362 (-2085 4110);
PAINT MONO (-2085 4110);
FORCEPROP 0 LASTPIN (-2050 4050) $PN AU20
J 0
(-2085 4060);
DISPLAY 0.489362 (-2085 4060);
PAINT MONO (-2085 4060);
FORCEPROP 0 LASTPIN (-2050 4000) $PN AU22
J 0
(-2085 4010);
DISPLAY 0.489362 (-2085 4010);
PAINT MONO (-2085 4010);
FORCEPROP 0 LASTPIN (-2050 3950) $PN AU24
J 0
(-2085 3960);
DISPLAY 0.489362 (-2085 3960);
PAINT MONO (-2085 3960);
FORCEPROP 0 LASTPIN (-2050 3900) $PN AU26
J 0
(-2085 3910);
DISPLAY 0.489362 (-2085 3910);
PAINT MONO (-2085 3910);
FORCEPROP 0 LASTPIN (-2050 3850) $PN AU28
J 0
(-2085 3860);
DISPLAY 0.489362 (-2085 3860);
PAINT MONO (-2085 3860);
FORCEPROP 0 LASTPIN (-2050 3800) $PN AU30
J 0
(-2085 3810);
DISPLAY 0.489362 (-2085 3810);
PAINT MONO (-2085 3810);
FORCEPROP 0 LASTPIN (-2050 3750) $PN AU32
J 0
(-2085 3760);
DISPLAY 0.489362 (-2085 3760);
PAINT MONO (-2085 3760);
FORCEPROP 0 LASTPIN (-2050 3700) $PN AU34
J 0
(-2085 3710);
DISPLAY 0.489362 (-2085 3710);
PAINT MONO (-2085 3710);
FORCEPROP 0 LASTPIN (-2050 3650) $PN AU36
J 0
(-2085 3660);
DISPLAY 0.489362 (-2085 3660);
PAINT MONO (-2085 3660);
FORCEPROP 0 LASTPIN (-2050 3600) $PN AU41
J 0
(-2085 3610);
DISPLAY 0.489362 (-2085 3610);
PAINT MONO (-2085 3610);
FORCEPROP 0 LASTPIN (-2050 3550) $PN AU43
J 0
(-2085 3560);
DISPLAY 0.489362 (-2085 3560);
PAINT MONO (-2085 3560);
FORCEPROP 0 LASTPIN (-2050 3500) $PN AU45
J 0
(-2085 3510);
DISPLAY 0.489362 (-2085 3510);
PAINT MONO (-2085 3510);
FORCEPROP 0 LASTPIN (-2050 3450) $PN AU47
J 0
(-2085 3460);
DISPLAY 0.489362 (-2085 3460);
PAINT MONO (-2085 3460);
FORCEPROP 0 LASTPIN (-2050 3400) $PN AU49
J 0
(-2085 3410);
DISPLAY 0.489362 (-2085 3410);
PAINT MONO (-2085 3410);
FORCEPROP 0 LASTPIN (-2050 3350) $PN AU51
J 0
(-2085 3360);
DISPLAY 0.489362 (-2085 3360);
PAINT MONO (-2085 3360);
FORCEPROP 0 LASTPIN (-2050 3300) $PN AU53
J 0
(-2085 3310);
DISPLAY 0.489362 (-2085 3310);
PAINT MONO (-2085 3310);
FORCEPROP 0 LASTPIN (-2050 3250) $PN AU56
J 0
(-2085 3260);
DISPLAY 0.489362 (-2085 3260);
PAINT MONO (-2085 3260);
FORCEPROP 0 LASTPIN (-2050 3200) $PN AU58
J 0
(-2085 3210);
DISPLAY 0.489362 (-2085 3210);
PAINT MONO (-2085 3210);
FORCEPROP 0 LASTPIN (-2050 3150) $PN AU61
J 0
(-2085 3160);
DISPLAY 0.489362 (-2085 3160);
PAINT MONO (-2085 3160);
FORCEPROP 0 LASTPIN (-2050 3100) $PN AU63
J 0
(-2085 3110);
DISPLAY 0.489362 (-2085 3110);
PAINT MONO (-2085 3110);
FORCEPROP 0 LASTPIN (-2050 3050) $PN AU65
J 0
(-2085 3060);
DISPLAY 0.489362 (-2085 3060);
PAINT MONO (-2085 3060);
FORCEPROP 0 LASTPIN (-2050 3000) $PN AU68
J 0
(-2085 3010);
DISPLAY 0.489362 (-2085 3010);
PAINT MONO (-2085 3010);
FORCEPROP 0 LASTPIN (-2050 2950) $PN AU70
J 0
(-2085 2960);
DISPLAY 0.489362 (-2085 2960);
PAINT MONO (-2085 2960);
FORCEPROP 0 LASTPIN (-2050 2900) $PN AU72
J 0
(-2085 2910);
DISPLAY 0.489362 (-2085 2910);
PAINT MONO (-2085 2910);
FORCEPROP 0 LASTPIN (-2050 2850) $PN AU73
J 0
(-2085 2860);
DISPLAY 0.489362 (-2085 2860);
PAINT MONO (-2085 2860);
FORCEPROP 0 LASTPIN (-2050 2800) $PN AU75
J 0
(-2085 2810);
DISPLAY 0.489362 (-2085 2810);
PAINT MONO (-2085 2810);
FORCEPROP 0 LASTPIN (-2050 2750) $PN AV3
J 0
(-2085 2760);
DISPLAY 0.489362 (-2085 2760);
PAINT MONO (-2085 2760);
FORCEPROP 0 LASTPIN (-2050 2700) $PN AV8
J 0
(-2085 2710);
DISPLAY 0.489362 (-2085 2710);
PAINT MONO (-2085 2710);
FORCEPROP 0 LASTPIN (-2050 2650) $PN AV10
J 0
(-2085 2660);
DISPLAY 0.489362 (-2085 2660);
PAINT MONO (-2085 2660);
FORCEPROP 0 LASTPIN (-2050 2600) $PN AV15
J 0
(-2085 2610);
DISPLAY 0.489362 (-2085 2610);
PAINT MONO (-2085 2610);
FORCEPROP 0 LASTPIN (-2050 2550) $PN AV17
J 0
(-2085 2560);
DISPLAY 0.489362 (-2085 2560);
PAINT MONO (-2085 2560);
FORCEPROP 0 LASTPIN (-2050 2500) $PN AV23
J 0
(-2085 2510);
DISPLAY 0.489362 (-2085 2510);
PAINT MONO (-2085 2510);
FORCEPROP 0 LASTPIN (-2050 2450) $PN AV25
J 0
(-2085 2460);
DISPLAY 0.489362 (-2085 2460);
PAINT MONO (-2085 2460);
FORCEPROP 0 LASTPIN (-2050 2400) $PN AV27
J 0
(-2085 2410);
DISPLAY 0.489362 (-2085 2410);
PAINT MONO (-2085 2410);
FORCEPROP 0 LASTPIN (-2050 2350) $PN AV29
J 0
(-2085 2360);
DISPLAY 0.489362 (-2085 2360);
PAINT MONO (-2085 2360);
FORCEPROP 0 LASTPIN (-2050 2300) $PN AV31
J 0
(-2085 2310);
DISPLAY 0.489362 (-2085 2310);
PAINT MONO (-2085 2310);
FORCEPROP 0 LASTPIN (-2050 2250) $PN AV33
J 0
(-2085 2260);
DISPLAY 0.489362 (-2085 2260);
PAINT MONO (-2085 2260);
FORCEPROP 0 LASTPIN (-2050 2200) $PN AV35
J 0
(-2085 2210);
DISPLAY 0.489362 (-2085 2210);
PAINT MONO (-2085 2210);
FORCEPROP 0 LASTPIN (-2050 2150) $PN AV37
J 0
(-2085 2160);
DISPLAY 0.489362 (-2085 2160);
PAINT MONO (-2085 2160);
FORCEPROP 0 LASTPIN (-2050 2100) $PN AV40
J 0
(-2085 2110);
DISPLAY 0.489362 (-2085 2110);
PAINT MONO (-2085 2110);
FORCEPROP 0 LASTPIN (-2050 2050) $PN AV42
J 0
(-2085 2060);
DISPLAY 0.489362 (-2085 2060);
PAINT MONO (-2085 2060);
FORCEPROP 0 LASTPIN (-2050 2000) $PN AV44
J 0
(-2085 2010);
DISPLAY 0.489362 (-2085 2010);
PAINT MONO (-2085 2010);
FORCEPROP 0 LASTPIN (-2050 1950) $PN AV46
J 0
(-2085 1960);
DISPLAY 0.489362 (-2085 1960);
PAINT MONO (-2085 1960);
FORCEPROP 0 LASTPIN (-2050 1900) $PN AV48
J 0
(-2085 1910);
DISPLAY 0.489362 (-2085 1910);
PAINT MONO (-2085 1910);
FORCEPROP 0 LASTPIN (-2050 1850) $PN AV50
J 0
(-2085 1860);
DISPLAY 0.489362 (-2085 1860);
PAINT MONO (-2085 1860);
FORCEPROP 0 LASTPIN (-2050 1800) $PN AV52
J 0
(-2085 1810);
DISPLAY 0.489362 (-2085 1810);
PAINT MONO (-2085 1810);
FORCEPROP 0 LASTPIN (-2050 1750) $PN AV54
J 0
(-2085 1760);
DISPLAY 0.489362 (-2085 1760);
PAINT MONO (-2085 1760);
FORCEPROP 0 LASTPIN (-2050 1700) $PN AV59
J 0
(-2085 1710);
DISPLAY 0.489362 (-2085 1710);
PAINT MONO (-2085 1710);
FORCEPROP 0 LASTPIN (-2050 1650) $PN AV61
J 0
(-2085 1660);
DISPLAY 0.489362 (-2085 1660);
PAINT MONO (-2085 1660);
FORCEPROP 0 LASTPIN (-2050 1600) $PN AV66
J 0
(-2085 1610);
DISPLAY 0.489362 (-2085 1610);
PAINT MONO (-2085 1610);
FORCEPROP 0 LASTPIN (-2050 1550) $PN AV68
J 0
(-2085 1560);
DISPLAY 0.489362 (-2085 1560);
PAINT MONO (-2085 1560);
FORCEPROP 0 LASTPIN (-2050 1500) $PN AV73
J 0
(-2085 1510);
DISPLAY 0.489362 (-2085 1510);
PAINT MONO (-2085 1510);
FORCEPROP 0 LASTPIN (-2050 1450) $PN AW1
J 0
(-2085 1460);
DISPLAY 0.489362 (-2085 1460);
PAINT MONO (-2085 1460);
FORCEPROP 0 LASTPIN (-2050 1400) $PN AW4
J 0
(-2085 1410);
DISPLAY 0.489362 (-2085 1410);
PAINT MONO (-2085 1410);
FORCEPROP 0 LASTPIN (-2050 1350) $PN AW6
J 0
(-2085 1360);
DISPLAY 0.489362 (-2085 1360);
PAINT MONO (-2085 1360);
FORCEPROP 0 LASTPIN (-2050 1300) $PN AW8
J 0
(-2085 1310);
DISPLAY 0.489362 (-2085 1310);
PAINT MONO (-2085 1310);
FORCEPROP 0 LASTPIN (-2050 1250) $PN AW11
J 0
(-2085 1260);
DISPLAY 0.489362 (-2085 1260);
PAINT MONO (-2085 1260);
FORCEPROP 0 LASTPIN (-2050 1200) $PN AW13
J 0
(-2085 1210);
DISPLAY 0.489362 (-2085 1210);
PAINT MONO (-2085 1210);
FORCEPROP 0 LASTPIN (-2050 1150) $PN AW15
J 0
(-2085 1160);
DISPLAY 0.489362 (-2085 1160);
PAINT MONO (-2085 1160);
FORCEPROP 0 LASTPIN (-2050 1100) $PN AW18
J 0
(-2085 1110);
DISPLAY 0.489362 (-2085 1110);
PAINT MONO (-2085 1110);
FORCEPROP 0 LASTPIN (-2050 1050) $PN AW20
J 0
(-2085 1060);
DISPLAY 0.489362 (-2085 1060);
PAINT MONO (-2085 1060);
FORCEPROP 0 LASTPIN (-2050 1000) $PN AW22
J 0
(-2085 1010);
DISPLAY 0.489362 (-2085 1010);
PAINT MONO (-2085 1010);
FORCEPROP 0 LASTPIN (-2050 950) $PN AW24
J 0
(-2085 960);
DISPLAY 0.489362 (-2085 960);
PAINT MONO (-2085 960);
FORCEPROP 0 LASTPIN (-2050 900) $PN AW26
J 0
(-2085 910);
DISPLAY 0.489362 (-2085 910);
PAINT MONO (-2085 910);
FORCEPROP 0 LASTPIN (-2050 850) $PN AW28
J 0
(-2085 860);
DISPLAY 0.489362 (-2085 860);
PAINT MONO (-2085 860);
FORCEPROP 0 LASTPIN (-2050 800) $PN AW49
J 0
(-2085 810);
DISPLAY 0.489362 (-2085 810);
PAINT MONO (-2085 810);
FORCEPROP 0 LASTPIN (-2050 750) $PN AW51
J 0
(-2085 760);
DISPLAY 0.489362 (-2085 760);
PAINT MONO (-2085 760);
FORCEPROP 0 LASTPIN (-2050 700) $PN AW53
J 0
(-2085 710);
DISPLAY 0.489362 (-2085 710);
PAINT MONO (-2085 710);
FORCEPROP 0 LASTPIN (-2050 650) $PN AW56
J 0
(-2085 660);
DISPLAY 0.489362 (-2085 660);
PAINT MONO (-2085 660);
FORCEPROP 0 LASTPIN (-2050 600) $PN AW58
J 0
(-2085 610);
DISPLAY 0.489362 (-2085 610);
PAINT MONO (-2085 610);
FORCEPROP 0 LASTPIN (-2050 550) $PN AW61
J 0
(-2085 560);
DISPLAY 0.489362 (-2085 560);
PAINT MONO (-2085 560);
FORCEPROP 2 LAST PART_TYPE SMLF
J 0
(-3200 6700);
DISPLAY 1.021277 (-3200 6700);
FORCEPROP 1 LAST MATERIAL IO
J 0
(-2995 6582);
DISPLAY 0.489362 (-2995 6582);
PAINT SKYBLUE (-2995 6582);
FORCEPROP 2 LAST VALUE SOCKET6096_13568-001
J 0
(-3000 6625);
DISPLAY 0.489362 (-3000 6625);
PAINT SKYBLUE (-3000 6625);
FORCEPROP 2 LAST CDS_LIB pure_quanta
J 0
(-2600 3500);
DISPLAY INVISIBLE (-2600 3500);
FORCEPROP 1 LAST CDS_LMAN_SYM_OUTLINE -400,3050,400,-3050
J 0
(-2600 3500);
DISPLAY 0.468085 (-2600 3500);
PAINT GREEN (-2600 3500);
DISPLAY INVISIBLE (-2600 3500);
FORCEPROP 1 LAST NEEDS_NO_SIZE TRUE
J 0
(-2600 3500);
DISPLAY 0.723404 (-2600 3500);
PAINT GREEN (-2600 3500);
DISPLAY INVISIBLE (-2600 3500);
FORCEPROP 1 LAST PATH I6
J 0
(-2600 3500);
DISPLAY 0.723404 (-2600 3500);
PAINT GREEN (-2600 3500);
DISPLAY INVISIBLE (-2600 3500);
FORCEPROP 1 LAST PART_NUMBER DGA^6000030
J 0
(-2995 6709);
DISPLAY 0.489362 (-2995 6709);
PAINT SKYBLUE (-2995 6709);
DISPLAY INVISIBLE (-2995 6709);
FORCEADD GENOA_SP5..31
(-4075 3500);
FORCEPROP 1 LAST LOCATION U26
J 0
(-4475 6650);
DISPLAY 0.489362 (-4475 6650);
PAINT SKYBLUE (-4475 6650);
FORCEPROP 0 LAST $SEC 31
J 0
(-4450 6900);
DISPLAY 0.680851 (-4450 6900);
PAINT MONO (-4450 6900);
DISPLAY INVISIBLE (-4450 6900);
FORCEPROP 0 LAST CDS_SEC 31
J 0
(-4450 6900);
DISPLAY 1.021277 (-4450 6900);
DISPLAY INVISIBLE (-4450 6900);
FORCEPROP 0 LASTPIN (-4625 6400) $PN AD49
J 2
(-4585 6410);
DISPLAY 0.489362 (-4585 6410);
PAINT MONO (-4585 6410);
FORCEPROP 0 LASTPIN (-4625 6350) $PN AD50
J 2
(-4585 6360);
DISPLAY 0.489362 (-4585 6360);
PAINT MONO (-4585 6360);
FORCEPROP 0 LASTPIN (-4625 6300) $PN AD51
J 2
(-4585 6310);
DISPLAY 0.489362 (-4585 6310);
PAINT MONO (-4585 6310);
FORCEPROP 0 LASTPIN (-4625 6250) $PN AD52
J 2
(-4585 6260);
DISPLAY 0.489362 (-4585 6260);
PAINT MONO (-4585 6260);
FORCEPROP 0 LASTPIN (-4625 6200) $PN AD53
J 2
(-4585 6210);
DISPLAY 0.489362 (-4585 6210);
PAINT MONO (-4585 6210);
FORCEPROP 0 LASTPIN (-4625 6150) $PN AD57
J 2
(-4585 6160);
DISPLAY 0.489362 (-4585 6160);
PAINT MONO (-4585 6160);
FORCEPROP 0 LASTPIN (-4625 6100) $PN AD59
J 2
(-4585 6110);
DISPLAY 0.489362 (-4585 6110);
PAINT MONO (-4585 6110);
FORCEPROP 0 LASTPIN (-4625 6050) $PN AD61
J 2
(-4585 6060);
DISPLAY 0.489362 (-4585 6060);
PAINT MONO (-4585 6060);
FORCEPROP 0 LASTPIN (-4625 6000) $PN AD64
J 2
(-4585 6010);
DISPLAY 0.489362 (-4585 6010);
PAINT MONO (-4585 6010);
FORCEPROP 0 LASTPIN (-4625 5950) $PN AD66
J 2
(-4585 5960);
DISPLAY 0.489362 (-4585 5960);
PAINT MONO (-4585 5960);
FORCEPROP 0 LASTPIN (-4625 5900) $PN AD68
J 2
(-4585 5910);
DISPLAY 0.489362 (-4585 5910);
PAINT MONO (-4585 5910);
FORCEPROP 0 LASTPIN (-4625 5850) $PN AD71
J 2
(-4585 5860);
DISPLAY 0.489362 (-4585 5860);
PAINT MONO (-4585 5860);
FORCEPROP 0 LASTPIN (-4625 5800) $PN AD73
J 2
(-4585 5810);
DISPLAY 0.489362 (-4585 5810);
PAINT MONO (-4585 5810);
FORCEPROP 0 LASTPIN (-4625 5750) $PN AE1
J 2
(-4585 5760);
DISPLAY 0.489362 (-4585 5760);
PAINT MONO (-4585 5760);
FORCEPROP 0 LASTPIN (-4625 5700) $PN AE6
J 2
(-4585 5710);
DISPLAY 0.489362 (-4585 5710);
PAINT MONO (-4585 5710);
FORCEPROP 0 LASTPIN (-4625 5650) $PN AE8
J 2
(-4585 5660);
DISPLAY 0.489362 (-4585 5660);
PAINT MONO (-4585 5660);
FORCEPROP 0 LASTPIN (-4625 5600) $PN AE11
J 2
(-4585 5610);
DISPLAY 0.489362 (-4585 5610);
PAINT MONO (-4585 5610);
FORCEPROP 0 LASTPIN (-4625 5550) $PN AE13
J 2
(-4585 5560);
DISPLAY 0.489362 (-4585 5560);
PAINT MONO (-4585 5560);
FORCEPROP 0 LASTPIN (-4625 5500) $PN AE15
J 2
(-4585 5510);
DISPLAY 0.489362 (-4585 5510);
PAINT MONO (-4585 5510);
FORCEPROP 0 LASTPIN (-4625 5450) $PN AE18
J 2
(-4585 5460);
DISPLAY 0.489362 (-4585 5460);
PAINT MONO (-4585 5460);
FORCEPROP 0 LASTPIN (-4625 5400) $PN AE20
J 2
(-4585 5410);
DISPLAY 0.489362 (-4585 5410);
PAINT MONO (-4585 5410);
FORCEPROP 0 LASTPIN (-4625 5350) $PN AE22
J 2
(-4585 5360);
DISPLAY 0.489362 (-4585 5360);
PAINT MONO (-4585 5360);
FORCEPROP 0 LASTPIN (-4625 5300) $PN AE25
J 2
(-4585 5310);
DISPLAY 0.489362 (-4585 5310);
PAINT MONO (-4585 5310);
FORCEPROP 0 LASTPIN (-4625 5250) $PN AE28
J 2
(-4585 5260);
DISPLAY 0.489362 (-4585 5260);
PAINT MONO (-4585 5260);
FORCEPROP 0 LASTPIN (-4625 5200) $PN AE31
J 2
(-4585 5210);
DISPLAY 0.489362 (-4585 5210);
PAINT MONO (-4585 5210);
FORCEPROP 0 LASTPIN (-4625 5150) $PN AE34
J 2
(-4585 5160);
DISPLAY 0.489362 (-4585 5160);
PAINT MONO (-4585 5160);
FORCEPROP 0 LASTPIN (-4625 5100) $PN AE35
J 2
(-4585 5110);
DISPLAY 0.489362 (-4585 5110);
PAINT MONO (-4585 5110);
FORCEPROP 0 LASTPIN (-4625 5050) $PN AE36
J 2
(-4585 5060);
DISPLAY 0.489362 (-4585 5060);
PAINT MONO (-4585 5060);
FORCEPROP 0 LASTPIN (-4625 5000) $PN AE40
J 2
(-4585 5010);
DISPLAY 0.489362 (-4585 5010);
PAINT MONO (-4585 5010);
FORCEPROP 0 LASTPIN (-4625 4950) $PN AE41
J 2
(-4585 4960);
DISPLAY 0.489362 (-4585 4960);
PAINT MONO (-4585 4960);
FORCEPROP 0 LASTPIN (-4625 4900) $PN AE42
J 2
(-4585 4910);
DISPLAY 0.489362 (-4585 4910);
PAINT MONO (-4585 4910);
FORCEPROP 0 LASTPIN (-4625 4850) $PN AE45
J 2
(-4585 4860);
DISPLAY 0.489362 (-4585 4860);
PAINT MONO (-4585 4860);
FORCEPROP 0 LASTPIN (-4625 4800) $PN AE48
J 2
(-4585 4810);
DISPLAY 0.489362 (-4585 4810);
PAINT MONO (-4585 4810);
FORCEPROP 0 LASTPIN (-4625 4750) $PN AE51
J 2
(-4585 4760);
DISPLAY 0.489362 (-4585 4760);
PAINT MONO (-4585 4760);
FORCEPROP 0 LASTPIN (-4625 4700) $PN AE54
J 2
(-4585 4710);
DISPLAY 0.489362 (-4585 4710);
PAINT MONO (-4585 4710);
FORCEPROP 0 LASTPIN (-4625 4650) $PN AE56
J 2
(-4585 4660);
DISPLAY 0.489362 (-4585 4660);
PAINT MONO (-4585 4660);
FORCEPROP 0 LASTPIN (-4625 4600) $PN AE58
J 2
(-4585 4610);
DISPLAY 0.489362 (-4585 4610);
PAINT MONO (-4585 4610);
FORCEPROP 0 LASTPIN (-4625 4550) $PN AE61
J 2
(-4585 4560);
DISPLAY 0.489362 (-4585 4560);
PAINT MONO (-4585 4560);
FORCEPROP 0 LASTPIN (-4625 4500) $PN AE63
J 2
(-4585 4510);
DISPLAY 0.489362 (-4585 4510);
PAINT MONO (-4585 4510);
FORCEPROP 0 LASTPIN (-4625 4450) $PN AE65
J 2
(-4585 4460);
DISPLAY 0.489362 (-4585 4460);
PAINT MONO (-4585 4460);
FORCEPROP 0 LASTPIN (-4625 4400) $PN AE68
J 2
(-4585 4410);
DISPLAY 0.489362 (-4585 4410);
PAINT MONO (-4585 4410);
FORCEPROP 0 LASTPIN (-4625 4350) $PN AE70
J 2
(-4585 4360);
DISPLAY 0.489362 (-4585 4360);
PAINT MONO (-4585 4360);
FORCEPROP 0 LASTPIN (-4625 4300) $PN AE72
J 2
(-4585 4310);
DISPLAY 0.489362 (-4585 4310);
PAINT MONO (-4585 4310);
FORCEPROP 0 LASTPIN (-4625 4250) $PN AE75
J 2
(-4585 4260);
DISPLAY 0.489362 (-4585 4260);
PAINT MONO (-4585 4260);
FORCEPROP 0 LASTPIN (-4625 4200) $PN AF3
J 2
(-4585 4210);
DISPLAY 0.489362 (-4585 4210);
PAINT MONO (-4585 4210);
FORCEPROP 0 LASTPIN (-4625 4150) $PN AF8
J 2
(-4585 4160);
DISPLAY 0.489362 (-4585 4160);
PAINT MONO (-4585 4160);
FORCEPROP 0 LASTPIN (-4625 4100) $PN AF10
J 2
(-4585 4110);
DISPLAY 0.489362 (-4585 4110);
PAINT MONO (-4585 4110);
FORCEPROP 0 LASTPIN (-4625 4050) $PN AF15
J 2
(-4585 4060);
DISPLAY 0.489362 (-4585 4060);
PAINT MONO (-4585 4060);
FORCEPROP 0 LASTPIN (-4625 4000) $PN AF17
J 2
(-4585 4010);
DISPLAY 0.489362 (-4585 4010);
PAINT MONO (-4585 4010);
FORCEPROP 0 LASTPIN (-4625 3950) $PN AF22
J 2
(-4585 3960);
DISPLAY 0.489362 (-4585 3960);
PAINT MONO (-4585 3960);
FORCEPROP 0 LASTPIN (-4625 3900) $PN AF25
J 2
(-4585 3910);
DISPLAY 0.489362 (-4585 3910);
PAINT MONO (-4585 3910);
FORCEPROP 0 LASTPIN (-4625 3850) $PN AF28
J 2
(-4585 3860);
DISPLAY 0.489362 (-4585 3860);
PAINT MONO (-4585 3860);
FORCEPROP 0 LASTPIN (-4625 3800) $PN AF31
J 2
(-4585 3810);
DISPLAY 0.489362 (-4585 3810);
PAINT MONO (-4585 3810);
FORCEPROP 0 LASTPIN (-4625 3750) $PN AF34
J 2
(-4585 3760);
DISPLAY 0.489362 (-4585 3760);
PAINT MONO (-4585 3760);
FORCEPROP 0 LASTPIN (-4625 3700) $PN AF37
J 2
(-4585 3710);
DISPLAY 0.489362 (-4585 3710);
PAINT MONO (-4585 3710);
FORCEPROP 0 LASTPIN (-4625 3650) $PN AF39
J 2
(-4585 3660);
DISPLAY 0.489362 (-4585 3660);
PAINT MONO (-4585 3660);
FORCEPROP 0 LASTPIN (-4625 3600) $PN AF42
J 2
(-4585 3610);
DISPLAY 0.489362 (-4585 3610);
PAINT MONO (-4585 3610);
FORCEPROP 0 LASTPIN (-4625 3550) $PN AF45
J 2
(-4585 3560);
DISPLAY 0.489362 (-4585 3560);
PAINT MONO (-4585 3560);
FORCEPROP 0 LASTPIN (-4625 3500) $PN AF48
J 2
(-4585 3510);
DISPLAY 0.489362 (-4585 3510);
PAINT MONO (-4585 3510);
FORCEPROP 0 LASTPIN (-4625 3450) $PN AF51
J 2
(-4585 3460);
DISPLAY 0.489362 (-4585 3460);
PAINT MONO (-4585 3460);
FORCEPROP 0 LASTPIN (-4625 3400) $PN AF54
J 2
(-4585 3410);
DISPLAY 0.489362 (-4585 3410);
PAINT MONO (-4585 3410);
FORCEPROP 0 LASTPIN (-4625 3350) $PN AF59
J 2
(-4585 3360);
DISPLAY 0.489362 (-4585 3360);
PAINT MONO (-4585 3360);
FORCEPROP 0 LASTPIN (-4625 3300) $PN AF61
J 2
(-4585 3310);
DISPLAY 0.489362 (-4585 3310);
PAINT MONO (-4585 3310);
FORCEPROP 0 LASTPIN (-4625 3250) $PN AF66
J 2
(-4585 3260);
DISPLAY 0.489362 (-4585 3260);
PAINT MONO (-4585 3260);
FORCEPROP 0 LASTPIN (-4625 3200) $PN AF68
J 2
(-4585 3210);
DISPLAY 0.489362 (-4585 3210);
PAINT MONO (-4585 3210);
FORCEPROP 0 LASTPIN (-4625 3150) $PN AF73
J 2
(-4585 3160);
DISPLAY 0.489362 (-4585 3160);
PAINT MONO (-4585 3160);
FORCEPROP 0 LASTPIN (-4625 3100) $PN AG1
J 2
(-4585 3110);
DISPLAY 0.489362 (-4585 3110);
PAINT MONO (-4585 3110);
FORCEPROP 0 LASTPIN (-4625 3050) $PN AG4
J 2
(-4585 3060);
DISPLAY 0.489362 (-4585 3060);
PAINT MONO (-4585 3060);
FORCEPROP 0 LASTPIN (-4625 3000) $PN AG6
J 2
(-4585 3010);
DISPLAY 0.489362 (-4585 3010);
PAINT MONO (-4585 3010);
FORCEPROP 0 LASTPIN (-4625 2950) $PN AG8
J 2
(-4585 2960);
DISPLAY 0.489362 (-4585 2960);
PAINT MONO (-4585 2960);
FORCEPROP 0 LASTPIN (-4625 2900) $PN AG11
J 2
(-4585 2910);
DISPLAY 0.489362 (-4585 2910);
PAINT MONO (-4585 2910);
FORCEPROP 0 LASTPIN (-4625 2850) $PN AG13
J 2
(-4585 2860);
DISPLAY 0.489362 (-4585 2860);
PAINT MONO (-4585 2860);
FORCEPROP 0 LASTPIN (-4625 2800) $PN AG15
J 2
(-4585 2810);
DISPLAY 0.489362 (-4585 2810);
PAINT MONO (-4585 2810);
FORCEPROP 0 LASTPIN (-4625 2750) $PN AG18
J 2
(-4585 2760);
DISPLAY 0.489362 (-4585 2760);
PAINT MONO (-4585 2760);
FORCEPROP 0 LASTPIN (-4625 2700) $PN AG20
J 2
(-4585 2710);
DISPLAY 0.489362 (-4585 2710);
PAINT MONO (-4585 2710);
FORCEPROP 0 LASTPIN (-4625 2650) $PN AG22
J 2
(-4585 2660);
DISPLAY 0.489362 (-4585 2660);
PAINT MONO (-4585 2660);
FORCEPROP 0 LASTPIN (-4625 2600) $PN AG25
J 2
(-4585 2610);
DISPLAY 0.489362 (-4585 2610);
PAINT MONO (-4585 2610);
FORCEPROP 0 LASTPIN (-4625 2550) $PN AG28
J 2
(-4585 2560);
DISPLAY 0.489362 (-4585 2560);
PAINT MONO (-4585 2560);
FORCEPROP 0 LASTPIN (-4625 2500) $PN AG31
J 2
(-4585 2510);
DISPLAY 0.489362 (-4585 2510);
PAINT MONO (-4585 2510);
FORCEPROP 0 LASTPIN (-4625 2450) $PN AG34
J 2
(-4585 2460);
DISPLAY 0.489362 (-4585 2460);
PAINT MONO (-4585 2460);
FORCEPROP 0 LASTPIN (-4625 2400) $PN AG42
J 2
(-4585 2410);
DISPLAY 0.489362 (-4585 2410);
PAINT MONO (-4585 2410);
FORCEPROP 0 LASTPIN (-4625 2350) $PN AG45
J 2
(-4585 2360);
DISPLAY 0.489362 (-4585 2360);
PAINT MONO (-4585 2360);
FORCEPROP 0 LASTPIN (-4625 2300) $PN AG48
J 2
(-4585 2310);
DISPLAY 0.489362 (-4585 2310);
PAINT MONO (-4585 2310);
FORCEPROP 0 LASTPIN (-4625 2250) $PN AG51
J 2
(-4585 2260);
DISPLAY 0.489362 (-4585 2260);
PAINT MONO (-4585 2260);
FORCEPROP 0 LASTPIN (-4625 2200) $PN AG54
J 2
(-4585 2210);
DISPLAY 0.489362 (-4585 2210);
PAINT MONO (-4585 2210);
FORCEPROP 0 LASTPIN (-4625 2150) $PN AG56
J 2
(-4585 2160);
DISPLAY 0.489362 (-4585 2160);
PAINT MONO (-4585 2160);
FORCEPROP 0 LASTPIN (-4625 2100) $PN AG58
J 2
(-4585 2110);
DISPLAY 0.489362 (-4585 2110);
PAINT MONO (-4585 2110);
FORCEPROP 0 LASTPIN (-4625 2050) $PN AG61
J 2
(-4585 2060);
DISPLAY 0.489362 (-4585 2060);
PAINT MONO (-4585 2060);
FORCEPROP 0 LASTPIN (-4625 2000) $PN AG63
J 2
(-4585 2010);
DISPLAY 0.489362 (-4585 2010);
PAINT MONO (-4585 2010);
FORCEPROP 0 LASTPIN (-4625 1950) $PN AG65
J 2
(-4585 1960);
DISPLAY 0.489362 (-4585 1960);
PAINT MONO (-4585 1960);
FORCEPROP 0 LASTPIN (-4625 1900) $PN AG68
J 2
(-4585 1910);
DISPLAY 0.489362 (-4585 1910);
PAINT MONO (-4585 1910);
FORCEPROP 0 LASTPIN (-4625 1850) $PN AG70
J 2
(-4585 1860);
DISPLAY 0.489362 (-4585 1860);
PAINT MONO (-4585 1860);
FORCEPROP 0 LASTPIN (-4625 1800) $PN AG72
J 2
(-4585 1810);
DISPLAY 0.489362 (-4585 1810);
PAINT MONO (-4585 1810);
FORCEPROP 0 LASTPIN (-4625 1750) $PN AG75
J 2
(-4585 1760);
DISPLAY 0.489362 (-4585 1760);
PAINT MONO (-4585 1760);
FORCEPROP 0 LASTPIN (-4625 1700) $PN AH3
J 2
(-4585 1710);
DISPLAY 0.489362 (-4585 1710);
PAINT MONO (-4585 1710);
FORCEPROP 0 LASTPIN (-4625 1650) $PN AH5
J 2
(-4585 1660);
DISPLAY 0.489362 (-4585 1660);
PAINT MONO (-4585 1660);
FORCEPROP 0 LASTPIN (-4625 1600) $PN AH8
J 2
(-4585 1610);
DISPLAY 0.489362 (-4585 1610);
PAINT MONO (-4585 1610);
FORCEPROP 0 LASTPIN (-4625 1550) $PN AH10
J 2
(-4585 1560);
DISPLAY 0.489362 (-4585 1560);
PAINT MONO (-4585 1560);
FORCEPROP 0 LASTPIN (-4625 1500) $PN AH12
J 2
(-4585 1510);
DISPLAY 0.489362 (-4585 1510);
PAINT MONO (-4585 1510);
FORCEPROP 0 LASTPIN (-4625 1450) $PN AH15
J 2
(-4585 1460);
DISPLAY 0.489362 (-4585 1460);
PAINT MONO (-4585 1460);
FORCEPROP 0 LASTPIN (-4625 1400) $PN AH17
J 2
(-4585 1410);
DISPLAY 0.489362 (-4585 1410);
PAINT MONO (-4585 1410);
FORCEPROP 0 LASTPIN (-4625 1350) $PN AH19
J 2
(-4585 1360);
DISPLAY 0.489362 (-4585 1360);
PAINT MONO (-4585 1360);
FORCEPROP 0 LASTPIN (-4625 1300) $PN AH23
J 2
(-4585 1310);
DISPLAY 0.489362 (-4585 1310);
PAINT MONO (-4585 1310);
FORCEPROP 0 LASTPIN (-4625 1250) $PN AH24
J 2
(-4585 1260);
DISPLAY 0.489362 (-4585 1260);
PAINT MONO (-4585 1260);
FORCEPROP 0 LASTPIN (-4625 1200) $PN AH25
J 2
(-4585 1210);
DISPLAY 0.489362 (-4585 1210);
PAINT MONO (-4585 1210);
FORCEPROP 0 LASTPIN (-4625 1150) $PN AH26
J 2
(-4585 1160);
DISPLAY 0.489362 (-4585 1160);
PAINT MONO (-4585 1160);
FORCEPROP 0 LASTPIN (-4625 1100) $PN AH27
J 2
(-4585 1110);
DISPLAY 0.489362 (-4585 1110);
PAINT MONO (-4585 1110);
FORCEPROP 0 LASTPIN (-4625 1050) $PN AH28
J 2
(-4585 1060);
DISPLAY 0.489362 (-4585 1060);
PAINT MONO (-4585 1060);
FORCEPROP 0 LASTPIN (-4625 1000) $PN AH29
J 2
(-4585 1010);
DISPLAY 0.489362 (-4585 1010);
PAINT MONO (-4585 1010);
FORCEPROP 0 LASTPIN (-4625 950) $PN AH30
J 2
(-4585 960);
DISPLAY 0.489362 (-4585 960);
PAINT MONO (-4585 960);
FORCEPROP 0 LASTPIN (-4625 900) $PN AH31
J 2
(-4585 910);
DISPLAY 0.489362 (-4585 910);
PAINT MONO (-4585 910);
FORCEPROP 0 LASTPIN (-4625 850) $PN AH32
J 2
(-4585 860);
DISPLAY 0.489362 (-4585 860);
PAINT MONO (-4585 860);
FORCEPROP 0 LASTPIN (-4625 800) $PN AH34
J 2
(-4585 810);
DISPLAY 0.489362 (-4585 810);
PAINT MONO (-4585 810);
FORCEPROP 0 LASTPIN (-4625 750) $PN AH37
J 2
(-4585 760);
DISPLAY 0.489362 (-4585 760);
PAINT MONO (-4585 760);
FORCEPROP 0 LASTPIN (-4625 700) $PN AH39
J 2
(-4585 710);
DISPLAY 0.489362 (-4585 710);
PAINT MONO (-4585 710);
FORCEPROP 0 LASTPIN (-4625 650) $PN AH42
J 2
(-4585 660);
DISPLAY 0.489362 (-4585 660);
PAINT MONO (-4585 660);
FORCEPROP 0 LASTPIN (-4625 600) $PN AH43
J 2
(-4585 610);
DISPLAY 0.489362 (-4585 610);
PAINT MONO (-4585 610);
FORCEPROP 0 LASTPIN (-3525 6400) $PN AH44
J 0
(-3560 6410);
DISPLAY 0.489362 (-3560 6410);
PAINT MONO (-3560 6410);
FORCEPROP 0 LASTPIN (-3525 6350) $PN AH45
J 0
(-3560 6360);
DISPLAY 0.489362 (-3560 6360);
PAINT MONO (-3560 6360);
FORCEPROP 0 LASTPIN (-3525 6300) $PN AH46
J 0
(-3560 6310);
DISPLAY 0.489362 (-3560 6310);
PAINT MONO (-3560 6310);
FORCEPROP 0 LASTPIN (-3525 6250) $PN AH47
J 0
(-3560 6260);
DISPLAY 0.489362 (-3560 6260);
PAINT MONO (-3560 6260);
FORCEPROP 0 LASTPIN (-3525 6200) $PN AH48
J 0
(-3560 6210);
DISPLAY 0.489362 (-3560 6210);
PAINT MONO (-3560 6210);
FORCEPROP 0 LASTPIN (-3525 6150) $PN AH49
J 0
(-3560 6160);
DISPLAY 0.489362 (-3560 6160);
PAINT MONO (-3560 6160);
FORCEPROP 0 LASTPIN (-3525 6100) $PN AH50
J 0
(-3560 6110);
DISPLAY 0.489362 (-3560 6110);
PAINT MONO (-3560 6110);
FORCEPROP 0 LASTPIN (-3525 6050) $PN AH51
J 0
(-3560 6060);
DISPLAY 0.489362 (-3560 6060);
PAINT MONO (-3560 6060);
FORCEPROP 0 LASTPIN (-3525 6000) $PN AH52
J 0
(-3560 6010);
DISPLAY 0.489362 (-3560 6010);
PAINT MONO (-3560 6010);
FORCEPROP 0 LASTPIN (-3525 5950) $PN AH53
J 0
(-3560 5960);
DISPLAY 0.489362 (-3560 5960);
PAINT MONO (-3560 5960);
FORCEPROP 0 LASTPIN (-3525 5900) $PN AH57
J 0
(-3560 5910);
DISPLAY 0.489362 (-3560 5910);
PAINT MONO (-3560 5910);
FORCEPROP 0 LASTPIN (-3525 5850) $PN AH59
J 0
(-3560 5860);
DISPLAY 0.489362 (-3560 5860);
PAINT MONO (-3560 5860);
FORCEPROP 0 LASTPIN (-3525 5800) $PN AH61
J 0
(-3560 5810);
DISPLAY 0.489362 (-3560 5810);
PAINT MONO (-3560 5810);
FORCEPROP 0 LASTPIN (-3525 5750) $PN AH64
J 0
(-3560 5760);
DISPLAY 0.489362 (-3560 5760);
PAINT MONO (-3560 5760);
FORCEPROP 0 LASTPIN (-3525 5700) $PN AH66
J 0
(-3560 5710);
DISPLAY 0.489362 (-3560 5710);
PAINT MONO (-3560 5710);
FORCEPROP 0 LASTPIN (-3525 5650) $PN AH68
J 0
(-3560 5660);
DISPLAY 0.489362 (-3560 5660);
PAINT MONO (-3560 5660);
FORCEPROP 0 LASTPIN (-3525 5600) $PN AH71
J 0
(-3560 5610);
DISPLAY 0.489362 (-3560 5610);
PAINT MONO (-3560 5610);
FORCEPROP 0 LASTPIN (-3525 5550) $PN AH73
J 0
(-3560 5560);
DISPLAY 0.489362 (-3560 5560);
PAINT MONO (-3560 5560);
FORCEPROP 0 LASTPIN (-3525 5500) $PN AJ1
J 0
(-3560 5510);
DISPLAY 0.489362 (-3560 5510);
PAINT MONO (-3560 5510);
FORCEPROP 0 LASTPIN (-3525 5450) $PN AJ6
J 0
(-3560 5460);
DISPLAY 0.489362 (-3560 5460);
PAINT MONO (-3560 5460);
FORCEPROP 0 LASTPIN (-3525 5400) $PN AJ8
J 0
(-3560 5410);
DISPLAY 0.489362 (-3560 5410);
PAINT MONO (-3560 5410);
FORCEPROP 0 LASTPIN (-3525 5350) $PN AJ15
J 0
(-3560 5360);
DISPLAY 0.489362 (-3560 5360);
PAINT MONO (-3560 5360);
FORCEPROP 0 LASTPIN (-3525 5300) $PN AJ20
J 0
(-3560 5310);
DISPLAY 0.489362 (-3560 5310);
PAINT MONO (-3560 5310);
FORCEPROP 0 LASTPIN (-3525 5250) $PN AJ22
J 0
(-3560 5260);
DISPLAY 0.489362 (-3560 5260);
PAINT MONO (-3560 5260);
FORCEPROP 0 LASTPIN (-3525 5200) $PN AJ25
J 0
(-3560 5210);
DISPLAY 0.489362 (-3560 5210);
PAINT MONO (-3560 5210);
FORCEPROP 0 LASTPIN (-3525 5150) $PN AJ28
J 0
(-3560 5160);
DISPLAY 0.489362 (-3560 5160);
PAINT MONO (-3560 5160);
FORCEPROP 0 LASTPIN (-3525 5100) $PN AJ31
J 0
(-3560 5110);
DISPLAY 0.489362 (-3560 5110);
PAINT MONO (-3560 5110);
FORCEPROP 0 LASTPIN (-3525 5050) $PN AJ34
J 0
(-3560 5060);
DISPLAY 0.489362 (-3560 5060);
PAINT MONO (-3560 5060);
FORCEPROP 0 LASTPIN (-3525 5000) $PN AJ35
J 0
(-3560 5010);
DISPLAY 0.489362 (-3560 5010);
PAINT MONO (-3560 5010);
FORCEPROP 0 LASTPIN (-3525 4950) $PN AJ36
J 0
(-3560 4960);
DISPLAY 0.489362 (-3560 4960);
PAINT MONO (-3560 4960);
FORCEPROP 0 LASTPIN (-3525 4900) $PN AJ40
J 0
(-3560 4910);
DISPLAY 0.489362 (-3560 4910);
PAINT MONO (-3560 4910);
FORCEPROP 0 LASTPIN (-3525 4850) $PN AJ41
J 0
(-3560 4860);
DISPLAY 0.489362 (-3560 4860);
PAINT MONO (-3560 4860);
FORCEPROP 0 LASTPIN (-3525 4800) $PN AJ42
J 0
(-3560 4810);
DISPLAY 0.489362 (-3560 4810);
PAINT MONO (-3560 4810);
FORCEPROP 0 LASTPIN (-3525 4750) $PN AJ45
J 0
(-3560 4760);
DISPLAY 0.489362 (-3560 4760);
PAINT MONO (-3560 4760);
FORCEPROP 0 LASTPIN (-3525 4700) $PN AJ48
J 0
(-3560 4710);
DISPLAY 0.489362 (-3560 4710);
PAINT MONO (-3560 4710);
FORCEPROP 0 LASTPIN (-3525 4650) $PN AJ51
J 0
(-3560 4660);
DISPLAY 0.489362 (-3560 4660);
PAINT MONO (-3560 4660);
FORCEPROP 0 LASTPIN (-3525 4600) $PN AJ54
J 0
(-3560 4610);
DISPLAY 0.489362 (-3560 4610);
PAINT MONO (-3560 4610);
FORCEPROP 0 LASTPIN (-3525 4550) $PN AJ56
J 0
(-3560 4560);
DISPLAY 0.489362 (-3560 4560);
PAINT MONO (-3560 4560);
FORCEPROP 0 LASTPIN (-3525 4500) $PN AJ61
J 0
(-3560 4510);
DISPLAY 0.489362 (-3560 4510);
PAINT MONO (-3560 4510);
FORCEPROP 0 LASTPIN (-3525 4450) $PN AJ63
J 0
(-3560 4460);
DISPLAY 0.489362 (-3560 4460);
PAINT MONO (-3560 4460);
FORCEPROP 0 LASTPIN (-3525 4400) $PN AJ68
J 0
(-3560 4410);
DISPLAY 0.489362 (-3560 4410);
PAINT MONO (-3560 4410);
FORCEPROP 0 LASTPIN (-3525 4350) $PN AJ70
J 0
(-3560 4360);
DISPLAY 0.489362 (-3560 4360);
PAINT MONO (-3560 4360);
FORCEPROP 0 LASTPIN (-3525 4300) $PN AJ75
J 0
(-3560 4310);
DISPLAY 0.489362 (-3560 4310);
PAINT MONO (-3560 4310);
FORCEPROP 0 LASTPIN (-3525 4250) $PN AK3
J 0
(-3560 4260);
DISPLAY 0.489362 (-3560 4260);
PAINT MONO (-3560 4260);
FORCEPROP 0 LASTPIN (-3525 4200) $PN AK5
J 0
(-3560 4210);
DISPLAY 0.489362 (-3560 4210);
PAINT MONO (-3560 4210);
FORCEPROP 0 LASTPIN (-3525 4150) $PN AK8
J 0
(-3560 4160);
DISPLAY 0.489362 (-3560 4160);
PAINT MONO (-3560 4160);
FORCEPROP 0 LASTPIN (-3525 4100) $PN AK10
J 0
(-3560 4110);
DISPLAY 0.489362 (-3560 4110);
PAINT MONO (-3560 4110);
FORCEPROP 0 LASTPIN (-3525 4050) $PN AK12
J 0
(-3560 4060);
DISPLAY 0.489362 (-3560 4060);
PAINT MONO (-3560 4060);
FORCEPROP 0 LASTPIN (-3525 4000) $PN AK15
J 0
(-3560 4010);
DISPLAY 0.489362 (-3560 4010);
PAINT MONO (-3560 4010);
FORCEPROP 0 LASTPIN (-3525 3950) $PN AK17
J 0
(-3560 3960);
DISPLAY 0.489362 (-3560 3960);
PAINT MONO (-3560 3960);
FORCEPROP 0 LASTPIN (-3525 3900) $PN AK19
J 0
(-3560 3910);
DISPLAY 0.489362 (-3560 3910);
PAINT MONO (-3560 3910);
FORCEPROP 0 LASTPIN (-3525 3850) $PN AK22
J 0
(-3560 3860);
DISPLAY 0.489362 (-3560 3860);
PAINT MONO (-3560 3860);
FORCEPROP 0 LASTPIN (-3525 3800) $PN AK25
J 0
(-3560 3810);
DISPLAY 0.489362 (-3560 3810);
PAINT MONO (-3560 3810);
FORCEPROP 0 LASTPIN (-3525 3750) $PN AK28
J 0
(-3560 3760);
DISPLAY 0.489362 (-3560 3760);
PAINT MONO (-3560 3760);
FORCEPROP 0 LASTPIN (-3525 3700) $PN AK31
J 0
(-3560 3710);
DISPLAY 0.489362 (-3560 3710);
PAINT MONO (-3560 3710);
FORCEPROP 0 LASTPIN (-3525 3650) $PN AK34
J 0
(-3560 3660);
DISPLAY 0.489362 (-3560 3660);
PAINT MONO (-3560 3660);
FORCEPROP 0 LASTPIN (-3525 3600) $PN AK37
J 0
(-3560 3610);
DISPLAY 0.489362 (-3560 3610);
PAINT MONO (-3560 3610);
FORCEPROP 0 LASTPIN (-3525 3550) $PN AK39
J 0
(-3560 3560);
DISPLAY 0.489362 (-3560 3560);
PAINT MONO (-3560 3560);
FORCEPROP 0 LASTPIN (-3525 3500) $PN AK42
J 0
(-3560 3510);
DISPLAY 0.489362 (-3560 3510);
PAINT MONO (-3560 3510);
FORCEPROP 0 LASTPIN (-3525 3450) $PN AK45
J 0
(-3560 3460);
DISPLAY 0.489362 (-3560 3460);
PAINT MONO (-3560 3460);
FORCEPROP 0 LASTPIN (-3525 3400) $PN AK48
J 0
(-3560 3410);
DISPLAY 0.489362 (-3560 3410);
PAINT MONO (-3560 3410);
FORCEPROP 0 LASTPIN (-3525 3350) $PN AK51
J 0
(-3560 3360);
DISPLAY 0.489362 (-3560 3360);
PAINT MONO (-3560 3360);
FORCEPROP 0 LASTPIN (-3525 3300) $PN AK54
J 0
(-3560 3310);
DISPLAY 0.489362 (-3560 3310);
PAINT MONO (-3560 3310);
FORCEPROP 0 LASTPIN (-3525 3250) $PN AK57
J 0
(-3560 3260);
DISPLAY 0.489362 (-3560 3260);
PAINT MONO (-3560 3260);
FORCEPROP 0 LASTPIN (-3525 3200) $PN AK59
J 0
(-3560 3210);
DISPLAY 0.489362 (-3560 3210);
PAINT MONO (-3560 3210);
FORCEPROP 0 LASTPIN (-3525 3150) $PN AK61
J 0
(-3560 3160);
DISPLAY 0.489362 (-3560 3160);
PAINT MONO (-3560 3160);
FORCEPROP 0 LASTPIN (-3525 3100) $PN AK64
J 0
(-3560 3110);
DISPLAY 0.489362 (-3560 3110);
PAINT MONO (-3560 3110);
FORCEPROP 0 LASTPIN (-3525 3050) $PN AK66
J 0
(-3560 3060);
DISPLAY 0.489362 (-3560 3060);
PAINT MONO (-3560 3060);
FORCEPROP 0 LASTPIN (-3525 3000) $PN AK68
J 0
(-3560 3010);
DISPLAY 0.489362 (-3560 3010);
PAINT MONO (-3560 3010);
FORCEPROP 0 LASTPIN (-3525 2950) $PN AK71
J 0
(-3560 2960);
DISPLAY 0.489362 (-3560 2960);
PAINT MONO (-3560 2960);
FORCEPROP 0 LASTPIN (-3525 2900) $PN AK73
J 0
(-3560 2910);
DISPLAY 0.489362 (-3560 2910);
PAINT MONO (-3560 2910);
FORCEPROP 0 LASTPIN (-3525 2850) $PN AL1
J 0
(-3560 2860);
DISPLAY 0.489362 (-3560 2860);
PAINT MONO (-3560 2860);
FORCEPROP 0 LASTPIN (-3525 2800) $PN AL4
J 0
(-3560 2810);
DISPLAY 0.489362 (-3560 2810);
PAINT MONO (-3560 2810);
FORCEPROP 0 LASTPIN (-3525 2750) $PN AL6
J 0
(-3560 2760);
DISPLAY 0.489362 (-3560 2760);
PAINT MONO (-3560 2760);
FORCEPROP 0 LASTPIN (-3525 2700) $PN AL8
J 0
(-3560 2710);
DISPLAY 0.489362 (-3560 2710);
PAINT MONO (-3560 2710);
FORCEPROP 0 LASTPIN (-3525 2650) $PN AL11
J 0
(-3560 2660);
DISPLAY 0.489362 (-3560 2660);
PAINT MONO (-3560 2660);
FORCEPROP 0 LASTPIN (-3525 2600) $PN AL13
J 0
(-3560 2610);
DISPLAY 0.489362 (-3560 2610);
PAINT MONO (-3560 2610);
FORCEPROP 0 LASTPIN (-3525 2550) $PN AL15
J 0
(-3560 2560);
DISPLAY 0.489362 (-3560 2560);
PAINT MONO (-3560 2560);
FORCEPROP 0 LASTPIN (-3525 2500) $PN AL18
J 0
(-3560 2510);
DISPLAY 0.489362 (-3560 2510);
PAINT MONO (-3560 2510);
FORCEPROP 0 LASTPIN (-3525 2450) $PN AL20
J 0
(-3560 2460);
DISPLAY 0.489362 (-3560 2460);
PAINT MONO (-3560 2460);
FORCEPROP 0 LASTPIN (-3525 2400) $PN AL22
J 0
(-3560 2410);
DISPLAY 0.489362 (-3560 2410);
PAINT MONO (-3560 2410);
FORCEPROP 0 LASTPIN (-3525 2350) $PN AL25
J 0
(-3560 2360);
DISPLAY 0.489362 (-3560 2360);
PAINT MONO (-3560 2360);
FORCEPROP 0 LASTPIN (-3525 2300) $PN AL28
J 0
(-3560 2310);
DISPLAY 0.489362 (-3560 2310);
PAINT MONO (-3560 2310);
FORCEPROP 0 LASTPIN (-3525 2250) $PN AL31
J 0
(-3560 2260);
DISPLAY 0.489362 (-3560 2260);
PAINT MONO (-3560 2260);
FORCEPROP 0 LASTPIN (-3525 2200) $PN AL34
J 0
(-3560 2210);
DISPLAY 0.489362 (-3560 2210);
PAINT MONO (-3560 2210);
FORCEPROP 0 LASTPIN (-3525 2150) $PN AL42
J 0
(-3560 2160);
DISPLAY 0.489362 (-3560 2160);
PAINT MONO (-3560 2160);
FORCEPROP 0 LASTPIN (-3525 2100) $PN AL45
J 0
(-3560 2110);
DISPLAY 0.489362 (-3560 2110);
PAINT MONO (-3560 2110);
FORCEPROP 0 LASTPIN (-3525 2050) $PN AL48
J 0
(-3560 2060);
DISPLAY 0.489362 (-3560 2060);
PAINT MONO (-3560 2060);
FORCEPROP 0 LASTPIN (-3525 2000) $PN AL51
J 0
(-3560 2010);
DISPLAY 0.489362 (-3560 2010);
PAINT MONO (-3560 2010);
FORCEPROP 0 LASTPIN (-3525 1950) $PN AL54
J 0
(-3560 1960);
DISPLAY 0.489362 (-3560 1960);
PAINT MONO (-3560 1960);
FORCEPROP 0 LASTPIN (-3525 1900) $PN AL56
J 0
(-3560 1910);
DISPLAY 0.489362 (-3560 1910);
PAINT MONO (-3560 1910);
FORCEPROP 0 LASTPIN (-3525 1850) $PN AL58
J 0
(-3560 1860);
DISPLAY 0.489362 (-3560 1860);
PAINT MONO (-3560 1860);
FORCEPROP 0 LASTPIN (-3525 1800) $PN AL61
J 0
(-3560 1810);
DISPLAY 0.489362 (-3560 1810);
PAINT MONO (-3560 1810);
FORCEPROP 0 LASTPIN (-3525 1750) $PN AL63
J 0
(-3560 1760);
DISPLAY 0.489362 (-3560 1760);
PAINT MONO (-3560 1760);
FORCEPROP 0 LASTPIN (-3525 1700) $PN AL65
J 0
(-3560 1710);
DISPLAY 0.489362 (-3560 1710);
PAINT MONO (-3560 1710);
FORCEPROP 0 LASTPIN (-3525 1650) $PN AL68
J 0
(-3560 1660);
DISPLAY 0.489362 (-3560 1660);
PAINT MONO (-3560 1660);
FORCEPROP 0 LASTPIN (-3525 1600) $PN AL70
J 0
(-3560 1610);
DISPLAY 0.489362 (-3560 1610);
PAINT MONO (-3560 1610);
FORCEPROP 0 LASTPIN (-3525 1550) $PN AL72
J 0
(-3560 1560);
DISPLAY 0.489362 (-3560 1560);
PAINT MONO (-3560 1560);
FORCEPROP 0 LASTPIN (-3525 1500) $PN AL75
J 0
(-3560 1510);
DISPLAY 0.489362 (-3560 1510);
PAINT MONO (-3560 1510);
FORCEPROP 0 LASTPIN (-3525 1450) $PN AM3
J 0
(-3560 1460);
DISPLAY 0.489362 (-3560 1460);
PAINT MONO (-3560 1460);
FORCEPROP 0 LASTPIN (-3525 1400) $PN AM8
J 0
(-3560 1410);
DISPLAY 0.489362 (-3560 1410);
PAINT MONO (-3560 1410);
FORCEPROP 0 LASTPIN (-3525 1350) $PN AM10
J 0
(-3560 1360);
DISPLAY 0.489362 (-3560 1360);
PAINT MONO (-3560 1360);
FORCEPROP 0 LASTPIN (-3525 1300) $PN AM15
J 0
(-3560 1310);
DISPLAY 0.489362 (-3560 1310);
PAINT MONO (-3560 1310);
FORCEPROP 0 LASTPIN (-3525 1250) $PN AM17
J 0
(-3560 1260);
DISPLAY 0.489362 (-3560 1260);
PAINT MONO (-3560 1260);
FORCEPROP 0 LASTPIN (-3525 1200) $PN AM23
J 0
(-3560 1210);
DISPLAY 0.489362 (-3560 1210);
PAINT MONO (-3560 1210);
FORCEPROP 0 LASTPIN (-3525 1150) $PN AM24
J 0
(-3560 1160);
DISPLAY 0.489362 (-3560 1160);
PAINT MONO (-3560 1160);
FORCEPROP 0 LASTPIN (-3525 1100) $PN AM25
J 0
(-3560 1110);
DISPLAY 0.489362 (-3560 1110);
PAINT MONO (-3560 1110);
FORCEPROP 0 LASTPIN (-3525 1050) $PN AM26
J 0
(-3560 1060);
DISPLAY 0.489362 (-3560 1060);
PAINT MONO (-3560 1060);
FORCEPROP 0 LASTPIN (-3525 1000) $PN AM27
J 0
(-3560 1010);
DISPLAY 0.489362 (-3560 1010);
PAINT MONO (-3560 1010);
FORCEPROP 0 LASTPIN (-3525 950) $PN AM28
J 0
(-3560 960);
DISPLAY 0.489362 (-3560 960);
PAINT MONO (-3560 960);
FORCEPROP 0 LASTPIN (-3525 900) $PN AM29
J 0
(-3560 910);
DISPLAY 0.489362 (-3560 910);
PAINT MONO (-3560 910);
FORCEPROP 0 LASTPIN (-3525 850) $PN AM30
J 0
(-3560 860);
DISPLAY 0.489362 (-3560 860);
PAINT MONO (-3560 860);
FORCEPROP 0 LASTPIN (-3525 800) $PN AM31
J 0
(-3560 810);
DISPLAY 0.489362 (-3560 810);
PAINT MONO (-3560 810);
FORCEPROP 0 LASTPIN (-3525 750) $PN AM32
J 0
(-3560 760);
DISPLAY 0.489362 (-3560 760);
PAINT MONO (-3560 760);
FORCEPROP 0 LASTPIN (-3525 700) $PN AM33
J 0
(-3560 710);
DISPLAY 0.489362 (-3560 710);
PAINT MONO (-3560 710);
FORCEPROP 0 LASTPIN (-3525 650) $PN AM34
J 0
(-3560 660);
DISPLAY 0.489362 (-3560 660);
PAINT MONO (-3560 660);
FORCEPROP 0 LASTPIN (-3525 600) $PN AM39
J 0
(-3560 610);
DISPLAY 0.489362 (-3560 610);
PAINT MONO (-3560 610);
FORCEPROP 2 LAST PART_TYPE SMLF
J 0
(-4675 6680);
DISPLAY 1.021277 (-4675 6680);
FORCEPROP 1 LAST MATERIAL IO
J 0
(-4470 6582);
DISPLAY 0.489362 (-4470 6582);
PAINT SKYBLUE (-4470 6582);
FORCEPROP 2 LAST VALUE SOCKET6096_13568-001
J 0
(-4475 6625);
DISPLAY 0.489362 (-4475 6625);
PAINT SKYBLUE (-4475 6625);
FORCEPROP 2 LAST CDS_LIB pure_quanta
J 0
(-4075 3500);
DISPLAY INVISIBLE (-4075 3500);
FORCEPROP 1 LAST CDS_LMAN_SYM_OUTLINE -400,3050,400,-3050
J 0
(-4075 3500);
DISPLAY 0.468085 (-4075 3500);
PAINT GREEN (-4075 3500);
DISPLAY INVISIBLE (-4075 3500);
FORCEPROP 1 LAST NEEDS_NO_SIZE TRUE
J 0
(-4075 3500);
DISPLAY 0.723404 (-4075 3500);
PAINT GREEN (-4075 3500);
DISPLAY INVISIBLE (-4075 3500);
FORCEPROP 1 LAST PATH I9
J 0
(-4075 3500);
DISPLAY 0.723404 (-4075 3500);
PAINT GREEN (-4075 3500);
DISPLAY INVISIBLE (-4075 3500);
FORCEPROP 1 LAST PART_NUMBER DGA^6000030
J 0
(-4475 6700);
DISPLAY 0.489362 (-4475 6700);
PAINT SKYBLUE (-4475 6700);
DISPLAY INVISIBLE (-4475 6700);
FORCEADD QUANTA_TITLE_BLOCK_C..1
(-100 100);
FORCEPROP 0 LAST CDS_CON_LAST_MODIFIED Thu Sep 14 16:12:01 2023
J 0
(-1985 115);
DISPLAY INVISIBLE (-1985 115);
FORCEPROP 1 LAST CUSTOM_TXT_CDS <CON_LAST_MODIFIED>
J 0
(-1985 115);
DISPLAY 0.978723 (-1985 115);
FORCEPROP 2 LAST CUSTOM_TXT_CDS <XR_PAGE_TITLE>
J 0
(-7990 5350);
DISPLAY 0.638298 (-7990 5350);
PAINT PINK (-7990 5350);
DISPLAY INVISIBLE (-7990 5350);
FORCEPROP 1 LAST CUSTOM_TXT_CDS <NAME_2>
J 0
(-3275 150);
FORCEPROP 1 LAST CUSTOM_TXT_CDS <NAME_1>
J 0
(-3275 275);
FORCEPROP 1 LAST CUSTOM_TXT_CDS <Q_NUMBER>
J 0
(-1503 203);
DISPLAY 1.212766 (-1503 203);
FORCEPROP 1 LAST CUSTOM_TXT_CDS <Q_PROJ>
J 0
(-2482 202);
DISPLAY 1.212766 (-2482 202);
FORCEPROP 1 LAST CUSTOM_TXT_CDS <Q_REV>
J 0
(-284 203);
DISPLAY 1.212766 (-284 203);
FORCEPROP 1 LAST CUSTOM_TXT_CDS <CON_PAGE_NUM> OF <CON_TOTAL_PAGES>
J 0
(-546 118);
DISPLAY 0.978723 (-546 118);
FORCEPROP 1 LAST Q_TITLE CPU1 VSS 1/3
J 0
(-9400 175);
DISPLAY 2.446809 (-9400 175);
PAINT GREEN (-9400 175);
FORCEPROP 2 LAST PAGE_BORDER TRUE
J 0
(-7990 5350);
DISPLAY 0.638298 (-7990 5350);
PAINT PINK (-7990 5350);
DISPLAY INVISIBLE (-7990 5350);
FORCEPROP 1 LAST CDS_LMAN_SYM_OUTLINE -9475,6775,100,-125
J 0
(-100 100);
DISPLAY 0.468085 (-100 100);
PAINT GREEN (-100 100);
DISPLAY INVISIBLE (-100 100);
FORCEPROP 2 LAST CDS_LIB pure_quanta
J 0
(-100 100);
DISPLAY INVISIBLE (-100 100);
FORCEPROP 2 LAST CDS_XR_PAGE_TITLE CR-58 : @T6G_MB_LIB.T6G(SCH_1):PAGE58
J 0
(-7990 5350);
DISPLAY 0.638298 (-7990 5350);
PAINT PINK (-7990 5350);
DISPLAY INVISIBLE (-7990 5350);
FORCEPROP 1 LAST Q_DEPT BU9
J 1
(-3863 149);
DISPLAY 1.957447 (-3863 149);
PAINT GREEN (-3863 149);
DISPLAY INVISIBLE (-3863 149);
FORCEPROP 1 LAST COMMENT_BODY TRUE
J 0
(-88 87);
DISPLAY 0.978723 (-88 87);
PAINT GREEN (-88 87);
DISPLAY INVISIBLE (-88 87);
WIRE 16 -1 (-7725 6300)(-7600 6300);
WIRE 16 -1 (-7725 6300)(-7725 6250);
WIRE 16 -1 (-7725 6250)(-7600 6250);
WIRE 16 -1 (-7725 6250)(-7725 6200);
WIRE 16 -1 (-7725 6200)(-7600 6200);
WIRE 16 -1 (-7725 6200)(-7725 6150);
WIRE 16 -1 (-7725 6150)(-7600 6150);
WIRE 16 -1 (-7725 6150)(-7725 6100);
WIRE 16 -1 (-7725 6100)(-7600 6100);
WIRE 16 -1 (-7725 6100)(-7725 6050);
WIRE 16 -1 (-7600 6050)(-7725 6050);
WIRE 16 -1 (-7725 6050)(-7725 6000);
WIRE 16 -1 (-7600 6000)(-7725 6000);
WIRE 16 -1 (-7725 6000)(-7725 5950);
WIRE 16 -1 (-7725 5950)(-7600 5950);
WIRE 16 -1 (-7725 5950)(-7725 5900);
WIRE 16 -1 (-7725 5900)(-7600 5900);
WIRE 16 -1 (-7725 5900)(-7725 5850);
WIRE 16 -1 (-7725 5850)(-7600 5850);
WIRE 16 -1 (-7725 5850)(-7725 5800);
WIRE 16 -1 (-7725 5800)(-7600 5800);
WIRE 16 -1 (-7725 5800)(-7725 5750);
WIRE 16 -1 (-7725 5750)(-7600 5750);
WIRE 16 -1 (-7725 5750)(-7725 5700);
WIRE 16 -1 (-7725 5700)(-7600 5700);
WIRE 16 -1 (-7725 5700)(-7725 5650);
WIRE 16 -1 (-7600 5650)(-7725 5650);
WIRE 16 -1 (-7725 5650)(-7725 5600);
WIRE 16 -1 (-7600 5600)(-7725 5600);
WIRE 16 -1 (-7725 5600)(-7725 5550);
WIRE 16 -1 (-7725 5550)(-7600 5550);
WIRE 16 -1 (-7725 5550)(-7725 5500);
WIRE 16 -1 (-7725 5500)(-7600 5500);
WIRE 16 -1 (-7725 5500)(-7725 5450);
WIRE 16 -1 (-7725 5450)(-7600 5450);
WIRE 16 -1 (-7725 5450)(-7725 5400);
WIRE 16 -1 (-7725 5400)(-7600 5400);
WIRE 16 -1 (-7725 5400)(-7725 5350);
WIRE 16 -1 (-7725 5350)(-7600 5350);
WIRE 16 -1 (-7725 5350)(-7725 5300);
WIRE 16 -1 (-7725 5300)(-7600 5300);
WIRE 16 -1 (-7725 5300)(-7725 5250);
WIRE 16 -1 (-7600 5250)(-7725 5250);
WIRE 16 -1 (-7725 5250)(-7725 5200);
WIRE 16 -1 (-7600 5200)(-7725 5200);
WIRE 16 -1 (-7725 5200)(-7725 5150);
WIRE 16 -1 (-7725 5150)(-7600 5150);
WIRE 16 -1 (-7725 5150)(-7725 5100);
WIRE 16 -1 (-7725 5100)(-7600 5100);
WIRE 16 -1 (-7725 5100)(-7725 5050);
WIRE 16 -1 (-7725 5050)(-7600 5050);
WIRE 16 -1 (-7725 5050)(-7725 5000);
WIRE 16 -1 (-7725 5000)(-7600 5000);
WIRE 16 -1 (-7725 5000)(-7725 4950);
WIRE 16 -1 (-7725 4950)(-7600 4950);
WIRE 16 -1 (-7725 4950)(-7725 4900);
WIRE 16 -1 (-7725 4900)(-7600 4900);
WIRE 16 -1 (-7725 4900)(-7725 4850);
WIRE 16 -1 (-7600 4850)(-7725 4850);
WIRE 16 -1 (-7725 4850)(-7725 4800);
WIRE 16 -1 (-7600 4800)(-7725 4800);
WIRE 16 -1 (-7725 4800)(-7725 4750);
WIRE 16 -1 (-7725 4750)(-7600 4750);
WIRE 16 -1 (-7725 4750)(-7725 4700);
WIRE 16 -1 (-7725 4700)(-7600 4700);
WIRE 16 -1 (-7725 4700)(-7725 4650);
WIRE 16 -1 (-7725 4650)(-7600 4650);
WIRE 16 -1 (-7725 4650)(-7725 4600);
WIRE 16 -1 (-7725 4600)(-7600 4600);
WIRE 16 -1 (-7725 4600)(-7725 4550);
WIRE 16 -1 (-7725 4550)(-7600 4550);
WIRE 16 -1 (-7725 4550)(-7725 4500);
WIRE 16 -1 (-7725 4500)(-7600 4500);
WIRE 16 -1 (-7725 4500)(-7725 4450);
WIRE 16 -1 (-7600 4450)(-7725 4450);
WIRE 16 -1 (-7725 4450)(-7725 4400);
WIRE 16 -1 (-7600 4400)(-7725 4400);
WIRE 16 -1 (-7725 4400)(-7725 4350);
WIRE 16 -1 (-7725 4350)(-7600 4350);
WIRE 16 -1 (-7725 4350)(-7725 4300);
WIRE 16 -1 (-7725 4300)(-7600 4300);
WIRE 16 -1 (-7725 4300)(-7725 4250);
WIRE 16 -1 (-7725 4250)(-7600 4250);
WIRE 16 -1 (-7725 4250)(-7725 4200);
WIRE 16 -1 (-7725 4200)(-7600 4200);
WIRE 16 -1 (-7725 4200)(-7725 4150);
WIRE 16 -1 (-7725 4150)(-7600 4150);
WIRE 16 -1 (-7725 4150)(-7725 4100);
WIRE 16 -1 (-7725 4100)(-7600 4100);
WIRE 16 -1 (-7725 4100)(-7725 4050);
WIRE 16 -1 (-7600 4050)(-7725 4050);
WIRE 16 -1 (-7725 4050)(-7725 4000);
WIRE 16 -1 (-7600 4000)(-7725 4000);
WIRE 16 -1 (-7725 4000)(-7725 3950);
WIRE 16 -1 (-7725 3950)(-7600 3950);
WIRE 16 -1 (-7725 3950)(-7725 3900);
WIRE 16 -1 (-7725 3900)(-7600 3900);
WIRE 16 -1 (-7725 3900)(-7725 3850);
WIRE 16 -1 (-7725 3850)(-7600 3850);
WIRE 16 -1 (-7725 3850)(-7725 3800);
WIRE 16 -1 (-7725 3800)(-7600 3800);
WIRE 16 -1 (-7725 3800)(-7725 3750);
WIRE 16 -1 (-7725 3750)(-7600 3750);
WIRE 16 -1 (-7725 3750)(-7725 3700);
WIRE 16 -1 (-7725 3700)(-7600 3700);
WIRE 16 -1 (-7725 3700)(-7725 3650);
WIRE 16 -1 (-7600 3650)(-7725 3650);
WIRE 16 -1 (-7725 3650)(-7725 3600);
WIRE 16 -1 (-7600 3600)(-7725 3600);
WIRE 16 -1 (-7725 3600)(-7725 3550);
WIRE 16 -1 (-7725 3550)(-7600 3550);
WIRE 16 -1 (-7725 3550)(-7725 3500);
WIRE 16 -1 (-7725 3500)(-7600 3500);
WIRE 16 -1 (-7725 3500)(-7725 3450);
WIRE 16 -1 (-7725 3450)(-7600 3450);
WIRE 16 -1 (-7725 3450)(-7725 3400);
WIRE 16 -1 (-7725 3400)(-7600 3400);
WIRE 16 -1 (-7725 3400)(-7725 3350);
WIRE 16 -1 (-7725 3350)(-7600 3350);
WIRE 16 -1 (-7725 3350)(-7725 3300);
WIRE 16 -1 (-7725 3300)(-7600 3300);
WIRE 16 -1 (-7725 3300)(-7725 3250);
WIRE 16 -1 (-7600 3250)(-7725 3250);
WIRE 16 -1 (-7725 3250)(-7725 3200);
WIRE 16 -1 (-7600 3200)(-7725 3200);
WIRE 16 -1 (-7725 3200)(-7725 3150);
WIRE 16 -1 (-7725 3150)(-7600 3150);
WIRE 16 -1 (-7725 3150)(-7725 3100);
WIRE 16 -1 (-7725 3100)(-7600 3100);
WIRE 16 -1 (-7725 3100)(-7725 3050);
WIRE 16 -1 (-7725 3050)(-7600 3050);
WIRE 16 -1 (-7725 3050)(-7725 3000);
WIRE 16 -1 (-7725 3000)(-7600 3000);
WIRE 16 -1 (-7725 3000)(-7725 2950);
WIRE 16 -1 (-7725 2950)(-7600 2950);
WIRE 16 -1 (-7725 2950)(-7725 2900);
WIRE 16 -1 (-7725 2900)(-7600 2900);
WIRE 16 -1 (-7725 2900)(-7725 2850);
WIRE 16 -1 (-7600 2850)(-7725 2850);
WIRE 16 -1 (-7725 2850)(-7725 2800);
WIRE 16 -1 (-7600 2800)(-7725 2800);
WIRE 16 -1 (-7725 2800)(-7725 2750);
WIRE 16 -1 (-7725 2750)(-7600 2750);
WIRE 16 -1 (-7725 2750)(-7725 2700);
WIRE 16 -1 (-7725 2700)(-7600 2700);
WIRE 16 -1 (-7725 2700)(-7725 2650);
WIRE 16 -1 (-7725 2650)(-7600 2650);
WIRE 16 -1 (-7725 2650)(-7725 2600);
WIRE 16 -1 (-7725 2600)(-7600 2600);
WIRE 16 -1 (-7725 2600)(-7725 2550);
WIRE 16 -1 (-7725 2550)(-7600 2550);
WIRE 16 -1 (-7725 2550)(-7725 2500);
WIRE 16 -1 (-7725 2500)(-7600 2500);
WIRE 16 -1 (-7725 2500)(-7725 2450);
WIRE 16 -1 (-7600 2450)(-7725 2450);
WIRE 16 -1 (-7725 2450)(-7725 2400);
WIRE 16 -1 (-7600 2400)(-7725 2400);
WIRE 16 -1 (-7725 2400)(-7725 2350);
WIRE 16 -1 (-7725 2350)(-7600 2350);
WIRE 16 -1 (-7725 2350)(-7725 2300);
WIRE 16 -1 (-7725 2300)(-7600 2300);
WIRE 16 -1 (-7725 2300)(-7725 2250);
WIRE 16 -1 (-7725 2250)(-7600 2250);
WIRE 16 -1 (-7725 2250)(-7725 2200);
WIRE 16 -1 (-7725 2200)(-7600 2200);
WIRE 16 -1 (-7725 2200)(-7725 2150);
WIRE 16 -1 (-7725 2150)(-7600 2150);
WIRE 16 -1 (-7725 2150)(-7725 2100);
WIRE 16 -1 (-7725 2100)(-7600 2100);
WIRE 16 -1 (-7725 2100)(-7725 2050);
WIRE 16 -1 (-7600 2050)(-7725 2050);
WIRE 16 -1 (-7725 2050)(-7725 2000);
WIRE 16 -1 (-7600 2000)(-7725 2000);
WIRE 16 -1 (-7725 2000)(-7725 1950);
WIRE 16 -1 (-7725 1950)(-7600 1950);
WIRE 16 -1 (-7725 1950)(-7725 1900);
WIRE 16 -1 (-7725 1900)(-7600 1900);
WIRE 16 -1 (-7725 1900)(-7725 1850);
WIRE 16 -1 (-7725 1850)(-7600 1850);
WIRE 16 -1 (-7725 1850)(-7725 1800);
WIRE 16 -1 (-7725 1800)(-7600 1800);
WIRE 16 -1 (-7725 1800)(-7725 1750);
WIRE 16 -1 (-7725 1750)(-7600 1750);
WIRE 16 -1 (-7725 1750)(-7725 1700);
WIRE 16 -1 (-7725 1700)(-7600 1700);
WIRE 16 -1 (-7725 1700)(-7725 1650);
WIRE 16 -1 (-7600 1650)(-7725 1650);
WIRE 16 -1 (-7725 1650)(-7725 1600);
WIRE 16 -1 (-7600 1600)(-7725 1600);
WIRE 16 -1 (-7725 1600)(-7725 1550);
WIRE 16 -1 (-7725 1550)(-7600 1550);
WIRE 16 -1 (-7725 1550)(-7725 1500);
WIRE 16 -1 (-7725 1500)(-7600 1500);
WIRE 16 -1 (-7725 1500)(-7725 1450);
WIRE 16 -1 (-7725 1450)(-7600 1450);
WIRE 16 -1 (-7725 1450)(-7725 1400);
WIRE 16 -1 (-7725 1400)(-7600 1400);
WIRE 16 -1 (-7725 1400)(-7725 1350);
WIRE 16 -1 (-7725 1350)(-7600 1350);
WIRE 16 -1 (-7725 1350)(-7725 1300);
WIRE 16 -1 (-7725 1300)(-7600 1300);
WIRE 16 -1 (-7725 1300)(-7725 1250);
WIRE 16 -1 (-7600 1250)(-7725 1250);
WIRE 16 -1 (-7725 1250)(-7725 1200);
WIRE 16 -1 (-7600 1200)(-7725 1200);
WIRE 16 -1 (-7725 1200)(-7725 1150);
WIRE 16 -1 (-7725 1150)(-7600 1150);
WIRE 16 -1 (-7725 1150)(-7725 1100);
WIRE 16 -1 (-7725 1100)(-7600 1100);
WIRE 16 -1 (-7725 1100)(-7725 1050);
WIRE 16 -1 (-7725 1050)(-7600 1050);
WIRE 16 -1 (-7725 1050)(-7725 1000);
WIRE 16 -1 (-7725 1000)(-7600 1000);
WIRE 16 -1 (-7725 1000)(-7725 950);
WIRE 16 -1 (-7725 950)(-7600 950);
WIRE 16 -1 (-7725 950)(-7725 900);
WIRE 16 -1 (-7725 900)(-7600 900);
WIRE 16 -1 (-7725 900)(-7725 850);
WIRE 16 -1 (-7600 850)(-7725 850);
WIRE 16 -1 (-7725 850)(-7725 800);
WIRE 16 -1 (-7600 800)(-7725 800);
WIRE 16 -1 (-7725 800)(-7725 750);
WIRE 16 -1 (-7600 750)(-7725 750);
WIRE 16 -1 (-7725 750)(-7725 700);
WIRE 16 -1 (-7600 700)(-7725 700);
WIRE 16 -1 (-7725 700)(-7725 650);
WIRE 16 -1 (-7600 650)(-7725 650);
WIRE 16 -1 (-7725 650)(-7725 600);
WIRE 16 -1 (-7600 600)(-7725 600);
WIRE 16 -1 (-7725 600)(-7725 550);
WIRE 16 -1 (-7600 550)(-7725 550);
WIRE 16 -1 (-7725 550)(-7725 500);
WIRE 16 -1 (-7600 500)(-7725 500);
WIRE 16 -1 (-7725 500)(-7725 450);
WIRE 16 -1 (-7900 625)(-7900 575);
WIRE 16 -1 (-7900 675)(-7900 625);
WIRE 16 -1 (-7900 625)(-8025 625);
WIRE 16 -1 (-7900 575)(-7900 525);
WIRE 16 -1 (-7900 575)(-8025 575);
WIRE 16 -1 (-7900 525)(-8025 525);
WIRE 16 -1 (-7900 525)(-7900 475);
WIRE 16 -1 (-7900 725)(-7900 675);
WIRE 16 -1 (-7900 675)(-8025 675);
WIRE 16 -1 (-7900 775)(-7900 725);
WIRE 16 -1 (-8025 725)(-7900 725);
WIRE 16 -1 (-7900 475)(-7900 450);
WIRE 16 -1 (-7900 475)(-8025 475);
WIRE 16 -1 (-7900 825)(-7900 775);
WIRE 16 -1 (-8025 775)(-7900 775);
WIRE 16 -1 (-7900 875)(-7900 825);
WIRE 16 -1 (-7900 825)(-8025 825);
WIRE 16 -1 (-7900 925)(-7900 875);
WIRE 16 -1 (-7900 875)(-8025 875);
WIRE 16 -1 (-7900 975)(-7900 925);
WIRE 16 -1 (-7900 925)(-8025 925);
WIRE 16 -1 (-7900 1025)(-7900 975);
WIRE 16 -1 (-7900 975)(-8025 975);
WIRE 16 -1 (-7900 1075)(-7900 1025);
WIRE 16 -1 (-7900 1025)(-8025 1025);
WIRE 16 -1 (-7900 1125)(-7900 1075);
WIRE 16 -1 (-7900 1075)(-8025 1075);
WIRE 16 -1 (-7900 1175)(-7900 1125);
WIRE 16 -1 (-8025 1125)(-7900 1125);
WIRE 16 -1 (-7900 1225)(-7900 1175);
WIRE 16 -1 (-8025 1175)(-7900 1175);
WIRE 16 -1 (-7900 1275)(-7900 1225);
WIRE 16 -1 (-7900 1225)(-8025 1225);
WIRE 16 -1 (-7900 1325)(-7900 1275);
WIRE 16 -1 (-7900 1275)(-8025 1275);
WIRE 16 -1 (-7900 1375)(-7900 1325);
WIRE 16 -1 (-7900 1325)(-8025 1325);
WIRE 16 -1 (-7900 1425)(-7900 1375);
WIRE 16 -1 (-7900 1375)(-8025 1375);
WIRE 16 -1 (-7900 1475)(-7900 1425);
WIRE 16 -1 (-7900 1425)(-8025 1425);
WIRE 16 -1 (-7900 1525)(-7900 1475);
WIRE 16 -1 (-7900 1475)(-8025 1475);
WIRE 16 -1 (-7900 1575)(-7900 1525);
WIRE 16 -1 (-8025 1525)(-7900 1525);
WIRE 16 -1 (-7900 1625)(-7900 1575);
WIRE 16 -1 (-8025 1575)(-7900 1575);
WIRE 16 -1 (-7900 1675)(-7900 1625);
WIRE 16 -1 (-7900 1625)(-8025 1625);
WIRE 16 -1 (-7900 1725)(-7900 1675);
WIRE 16 -1 (-7900 1675)(-8025 1675);
WIRE 16 -1 (-7900 1775)(-7900 1725);
WIRE 16 -1 (-7900 1725)(-8025 1725);
WIRE 16 -1 (-7900 1825)(-7900 1775);
WIRE 16 -1 (-7900 1775)(-8025 1775);
WIRE 16 -1 (-7900 1875)(-7900 1825);
WIRE 16 -1 (-7900 1825)(-8025 1825);
WIRE 16 -1 (-7900 1925)(-7900 1875);
WIRE 16 -1 (-7900 1875)(-8025 1875);
WIRE 16 -1 (-7900 1975)(-7900 1925);
WIRE 16 -1 (-8025 1925)(-7900 1925);
WIRE 16 -1 (-7900 2025)(-7900 1975);
WIRE 16 -1 (-8025 1975)(-7900 1975);
WIRE 16 -1 (-7900 2075)(-7900 2025);
WIRE 16 -1 (-7900 2025)(-8025 2025);
WIRE 16 -1 (-7900 2125)(-7900 2075);
WIRE 16 -1 (-7900 2075)(-8025 2075);
WIRE 16 -1 (-7900 2175)(-7900 2125);
WIRE 16 -1 (-7900 2125)(-8025 2125);
WIRE 16 -1 (-7900 2225)(-7900 2175);
WIRE 16 -1 (-7900 2175)(-8025 2175);
WIRE 16 -1 (-7900 2275)(-7900 2225);
WIRE 16 -1 (-7900 2225)(-8025 2225);
WIRE 16 -1 (-7900 2325)(-7900 2275);
WIRE 16 -1 (-7900 2275)(-8025 2275);
WIRE 16 -1 (-7900 2375)(-7900 2325);
WIRE 16 -1 (-8025 2325)(-7900 2325);
WIRE 16 -1 (-7900 2425)(-7900 2375);
WIRE 16 -1 (-8025 2375)(-7900 2375);
WIRE 16 -1 (-7900 2475)(-7900 2425);
WIRE 16 -1 (-7900 2425)(-8025 2425);
WIRE 16 -1 (-7900 2525)(-7900 2475);
WIRE 16 -1 (-7900 2475)(-8025 2475);
WIRE 16 -1 (-7900 2575)(-7900 2525);
WIRE 16 -1 (-7900 2525)(-8025 2525);
WIRE 16 -1 (-7900 2625)(-7900 2575);
WIRE 16 -1 (-7900 2575)(-8025 2575);
WIRE 16 -1 (-7900 2675)(-7900 2625);
WIRE 16 -1 (-7900 2625)(-8025 2625);
WIRE 16 -1 (-7900 2725)(-7900 2675);
WIRE 16 -1 (-7900 2675)(-8025 2675);
WIRE 16 -1 (-7900 2775)(-7900 2725);
WIRE 16 -1 (-8025 2725)(-7900 2725);
WIRE 16 -1 (-7900 2825)(-7900 2775);
WIRE 16 -1 (-8025 2775)(-7900 2775);
WIRE 16 -1 (-7900 2875)(-7900 2825);
WIRE 16 -1 (-7900 2825)(-8025 2825);
WIRE 16 -1 (-7900 2925)(-7900 2875);
WIRE 16 -1 (-7900 2875)(-8025 2875);
WIRE 16 -1 (-7900 2975)(-7900 2925);
WIRE 16 -1 (-7900 2925)(-8025 2925);
WIRE 16 -1 (-7900 3025)(-7900 2975);
WIRE 16 -1 (-7900 2975)(-8025 2975);
WIRE 16 -1 (-7900 3075)(-7900 3025);
WIRE 16 -1 (-7900 3025)(-8025 3025);
WIRE 16 -1 (-7900 3125)(-7900 3075);
WIRE 16 -1 (-7900 3075)(-8025 3075);
WIRE 16 -1 (-7900 3175)(-7900 3125);
WIRE 16 -1 (-8025 3125)(-7900 3125);
WIRE 16 -1 (-7900 3225)(-7900 3175);
WIRE 16 -1 (-8025 3175)(-7900 3175);
WIRE 16 -1 (-7900 3275)(-7900 3225);
WIRE 16 -1 (-7900 3225)(-8025 3225);
WIRE 16 -1 (-7900 3325)(-7900 3275);
WIRE 16 -1 (-7900 3275)(-8025 3275);
WIRE 16 -1 (-7900 3375)(-7900 3325);
WIRE 16 -1 (-7900 3325)(-8025 3325);
WIRE 16 -1 (-7900 3425)(-7900 3375);
WIRE 16 -1 (-7900 3375)(-8025 3375);
WIRE 16 -1 (-7900 3475)(-7900 3425);
WIRE 16 -1 (-7900 3425)(-8025 3425);
WIRE 16 -1 (-7900 3525)(-7900 3475);
WIRE 16 -1 (-7900 3475)(-8025 3475);
WIRE 16 -1 (-7900 3575)(-7900 3525);
WIRE 16 -1 (-8025 3525)(-7900 3525);
WIRE 16 -1 (-7900 3625)(-7900 3575);
WIRE 16 -1 (-8025 3575)(-7900 3575);
WIRE 16 -1 (-7900 3675)(-7900 3625);
WIRE 16 -1 (-7900 3625)(-8025 3625);
WIRE 16 -1 (-7900 3725)(-7900 3675);
WIRE 16 -1 (-7900 3675)(-8025 3675);
WIRE 16 -1 (-7900 3775)(-7900 3725);
WIRE 16 -1 (-7900 3725)(-8025 3725);
WIRE 16 -1 (-7900 3825)(-7900 3775);
WIRE 16 -1 (-7900 3775)(-8025 3775);
WIRE 16 -1 (-7900 3875)(-7900 3825);
WIRE 16 -1 (-7900 3825)(-8025 3825);
WIRE 16 -1 (-7900 3925)(-7900 3875);
WIRE 16 -1 (-7900 3875)(-8025 3875);
WIRE 16 -1 (-7900 3975)(-7900 3925);
WIRE 16 -1 (-8025 3925)(-7900 3925);
WIRE 16 -1 (-7900 4025)(-7900 3975);
WIRE 16 -1 (-8025 3975)(-7900 3975);
WIRE 16 -1 (-7900 4075)(-7900 4025);
WIRE 16 -1 (-7900 4025)(-8025 4025);
WIRE 16 -1 (-7900 4125)(-7900 4075);
WIRE 16 -1 (-7900 4075)(-8025 4075);
WIRE 16 -1 (-7900 4175)(-7900 4125);
WIRE 16 -1 (-7900 4125)(-8025 4125);
WIRE 16 -1 (-7900 4225)(-7900 4175);
WIRE 16 -1 (-7900 4175)(-8025 4175);
WIRE 16 -1 (-7900 4275)(-7900 4225);
WIRE 16 -1 (-7900 4225)(-8025 4225);
WIRE 16 -1 (-7900 4325)(-7900 4275);
WIRE 16 -1 (-7900 4275)(-8025 4275);
WIRE 16 -1 (-7900 4375)(-7900 4325);
WIRE 16 -1 (-8025 4325)(-7900 4325);
WIRE 16 -1 (-7900 4425)(-7900 4375);
WIRE 16 -1 (-8025 4375)(-7900 4375);
WIRE 16 -1 (-7900 4475)(-7900 4425);
WIRE 16 -1 (-7900 4425)(-8025 4425);
WIRE 16 -1 (-7900 4525)(-7900 4475);
WIRE 16 -1 (-7900 4475)(-8025 4475);
WIRE 16 -1 (-7900 4575)(-7900 4525);
WIRE 16 -1 (-7900 4525)(-8025 4525);
WIRE 16 -1 (-7900 4625)(-7900 4575);
WIRE 16 -1 (-7900 4575)(-8025 4575);
WIRE 16 -1 (-7900 4675)(-7900 4625);
WIRE 16 -1 (-7900 4625)(-8025 4625);
WIRE 16 -1 (-7900 4725)(-7900 4675);
WIRE 16 -1 (-7900 4675)(-8025 4675);
WIRE 16 -1 (-7900 4775)(-7900 4725);
WIRE 16 -1 (-8025 4725)(-7900 4725);
WIRE 16 -1 (-7900 4825)(-7900 4775);
WIRE 16 -1 (-8025 4775)(-7900 4775);
WIRE 16 -1 (-7900 4875)(-7900 4825);
WIRE 16 -1 (-7900 4825)(-8025 4825);
WIRE 16 -1 (-7900 4925)(-7900 4875);
WIRE 16 -1 (-7900 4875)(-8025 4875);
WIRE 16 -1 (-7900 4975)(-7900 4925);
WIRE 16 -1 (-7900 4925)(-8025 4925);
WIRE 16 -1 (-7900 5025)(-7900 4975);
WIRE 16 -1 (-7900 4975)(-8025 4975);
WIRE 16 -1 (-7900 5075)(-7900 5025);
WIRE 16 -1 (-7900 5025)(-8025 5025);
WIRE 16 -1 (-7900 5125)(-7900 5075);
WIRE 16 -1 (-7900 5075)(-8025 5075);
WIRE 16 -1 (-7900 5175)(-7900 5125);
WIRE 16 -1 (-8025 5125)(-7900 5125);
WIRE 16 -1 (-7900 5225)(-7900 5175);
WIRE 16 -1 (-8025 5175)(-7900 5175);
WIRE 16 -1 (-7900 5275)(-7900 5225);
WIRE 16 -1 (-7900 5225)(-8025 5225);
WIRE 16 -1 (-7900 5325)(-7900 5275);
WIRE 16 -1 (-7900 5275)(-8025 5275);
WIRE 16 -1 (-7900 5375)(-7900 5325);
WIRE 16 -1 (-7900 5325)(-8025 5325);
WIRE 16 -1 (-7900 5425)(-7900 5375);
WIRE 16 -1 (-7900 5375)(-8025 5375);
WIRE 16 -1 (-7900 5475)(-7900 5425);
WIRE 16 -1 (-7900 5425)(-8025 5425);
WIRE 16 -1 (-7900 5525)(-7900 5475);
WIRE 16 -1 (-7900 5475)(-8025 5475);
WIRE 16 -1 (-7900 5575)(-7900 5525);
WIRE 16 -1 (-8025 5525)(-7900 5525);
WIRE 16 -1 (-7900 5625)(-7900 5575);
WIRE 16 -1 (-8025 5575)(-7900 5575);
WIRE 16 -1 (-7900 5675)(-7900 5625);
WIRE 16 -1 (-7900 5625)(-8025 5625);
WIRE 16 -1 (-7900 5725)(-7900 5675);
WIRE 16 -1 (-7900 5675)(-8025 5675);
WIRE 16 -1 (-7900 5775)(-7900 5725);
WIRE 16 -1 (-7900 5725)(-8025 5725);
WIRE 16 -1 (-7900 5825)(-7900 5775);
WIRE 16 -1 (-7900 5775)(-8025 5775);
WIRE 16 -1 (-7900 5875)(-7900 5825);
WIRE 16 -1 (-7900 5825)(-8025 5825);
WIRE 16 -1 (-7900 5925)(-7900 5875);
WIRE 16 -1 (-7900 5875)(-8025 5875);
WIRE 16 -1 (-7900 5975)(-7900 5925);
WIRE 16 -1 (-8025 5925)(-7900 5925);
WIRE 16 -1 (-7900 6025)(-7900 5975);
WIRE 16 -1 (-8025 5975)(-7900 5975);
WIRE 16 -1 (-7900 6075)(-7900 6025);
WIRE 16 -1 (-8025 6025)(-7900 6025);
WIRE 16 -1 (-7900 6125)(-7900 6075);
WIRE 16 -1 (-8025 6075)(-7900 6075);
WIRE 16 -1 (-7900 6175)(-7900 6125);
WIRE 16 -1 (-8025 6125)(-7900 6125);
WIRE 16 -1 (-7900 6225)(-7900 6175);
WIRE 16 -1 (-8025 6175)(-7900 6175);
WIRE 16 -1 (-7900 6275)(-7900 6225);
WIRE 16 -1 (-8025 6225)(-7900 6225);
WIRE 16 -1 (-7900 6325)(-7900 6275);
WIRE 16 -1 (-8025 6275)(-7900 6275);
WIRE 16 -1 (-7900 6375)(-7900 6325);
WIRE 16 -1 (-7900 6325)(-8025 6325);
WIRE 16 -1 (-7900 6375)(-8025 6375);
WIRE 16 -1 (-9250 6375)(-9125 6375);
WIRE 16 -1 (-9250 6375)(-9250 6325);
WIRE 16 -1 (-9250 6325)(-9125 6325);
WIRE 16 -1 (-9250 6325)(-9250 6275);
WIRE 16 -1 (-9250 6275)(-9125 6275);
WIRE 16 -1 (-9250 6275)(-9250 6225);
WIRE 16 -1 (-9250 6225)(-9125 6225);
WIRE 16 -1 (-9250 6225)(-9250 6175);
WIRE 16 -1 (-9250 6175)(-9125 6175);
WIRE 16 -1 (-9250 6175)(-9250 6125);
WIRE 16 -1 (-9125 6125)(-9250 6125);
WIRE 16 -1 (-9250 6125)(-9250 6075);
WIRE 16 -1 (-9125 6075)(-9250 6075);
WIRE 16 -1 (-9250 6075)(-9250 6025);
WIRE 16 -1 (-9250 6025)(-9125 6025);
WIRE 16 -1 (-9250 6025)(-9250 5975);
WIRE 16 -1 (-9250 5975)(-9125 5975);
WIRE 16 -1 (-9250 5975)(-9250 5925);
WIRE 16 -1 (-9250 5925)(-9125 5925);
WIRE 16 -1 (-9250 5925)(-9250 5875);
WIRE 16 -1 (-9250 5875)(-9125 5875);
WIRE 16 -1 (-9250 5875)(-9250 5825);
WIRE 16 -1 (-9250 5825)(-9125 5825);
WIRE 16 -1 (-9250 5825)(-9250 5775);
WIRE 16 -1 (-9250 5775)(-9125 5775);
WIRE 16 -1 (-9250 5775)(-9250 5725);
WIRE 16 -1 (-9125 5725)(-9250 5725);
WIRE 16 -1 (-9250 5725)(-9250 5675);
WIRE 16 -1 (-9125 5675)(-9250 5675);
WIRE 16 -1 (-9250 5675)(-9250 5625);
WIRE 16 -1 (-9250 5625)(-9125 5625);
WIRE 16 -1 (-9250 5625)(-9250 5575);
WIRE 16 -1 (-9250 5575)(-9125 5575);
WIRE 16 -1 (-9250 5575)(-9250 5525);
WIRE 16 -1 (-9250 5525)(-9125 5525);
WIRE 16 -1 (-9250 5525)(-9250 5475);
WIRE 16 -1 (-9250 5475)(-9125 5475);
WIRE 16 -1 (-9250 5475)(-9250 5425);
WIRE 16 -1 (-9250 5425)(-9125 5425);
WIRE 16 -1 (-9250 5425)(-9250 5375);
WIRE 16 -1 (-9250 5375)(-9125 5375);
WIRE 16 -1 (-9250 5375)(-9250 5325);
WIRE 16 -1 (-9125 5325)(-9250 5325);
WIRE 16 -1 (-9250 5325)(-9250 5275);
WIRE 16 -1 (-9125 5275)(-9250 5275);
WIRE 16 -1 (-9250 5275)(-9250 5225);
WIRE 16 -1 (-9250 5225)(-9125 5225);
WIRE 16 -1 (-9250 5225)(-9250 5175);
WIRE 16 -1 (-9250 5175)(-9125 5175);
WIRE 16 -1 (-9250 5175)(-9250 5125);
WIRE 16 -1 (-9250 5125)(-9125 5125);
WIRE 16 -1 (-9250 5125)(-9250 5075);
WIRE 16 -1 (-9250 5075)(-9125 5075);
WIRE 16 -1 (-9250 5075)(-9250 5025);
WIRE 16 -1 (-9250 5025)(-9125 5025);
WIRE 16 -1 (-9250 5025)(-9250 4975);
WIRE 16 -1 (-9250 4975)(-9125 4975);
WIRE 16 -1 (-9250 4975)(-9250 4925);
WIRE 16 -1 (-9125 4925)(-9250 4925);
WIRE 16 -1 (-9250 4925)(-9250 4875);
WIRE 16 -1 (-9125 4875)(-9250 4875);
WIRE 16 -1 (-9250 4875)(-9250 4825);
WIRE 16 -1 (-9250 4825)(-9125 4825);
WIRE 16 -1 (-9250 4825)(-9250 4775);
WIRE 16 -1 (-9250 4775)(-9125 4775);
WIRE 16 -1 (-9250 4775)(-9250 4725);
WIRE 16 -1 (-9250 4725)(-9125 4725);
WIRE 16 -1 (-9250 4725)(-9250 4675);
WIRE 16 -1 (-9250 4675)(-9125 4675);
WIRE 16 -1 (-9250 4675)(-9250 4625);
WIRE 16 -1 (-9250 4625)(-9125 4625);
WIRE 16 -1 (-9250 4625)(-9250 4575);
WIRE 16 -1 (-9250 4575)(-9125 4575);
WIRE 16 -1 (-9250 4575)(-9250 4525);
WIRE 16 -1 (-9125 4525)(-9250 4525);
WIRE 16 -1 (-9250 4525)(-9250 4475);
WIRE 16 -1 (-9125 4475)(-9250 4475);
WIRE 16 -1 (-9250 4475)(-9250 4425);
WIRE 16 -1 (-9250 4425)(-9125 4425);
WIRE 16 -1 (-9250 4425)(-9250 4375);
WIRE 16 -1 (-9250 4375)(-9125 4375);
WIRE 16 -1 (-9250 4375)(-9250 4325);
WIRE 16 -1 (-9250 4325)(-9125 4325);
WIRE 16 -1 (-9250 4325)(-9250 4275);
WIRE 16 -1 (-9250 4275)(-9125 4275);
WIRE 16 -1 (-9250 4275)(-9250 4225);
WIRE 16 -1 (-9250 4225)(-9125 4225);
WIRE 16 -1 (-9250 4225)(-9250 4175);
WIRE 16 -1 (-9250 4175)(-9125 4175);
WIRE 16 -1 (-9250 4175)(-9250 4125);
WIRE 16 -1 (-9125 4125)(-9250 4125);
WIRE 16 -1 (-9250 4125)(-9250 4075);
WIRE 16 -1 (-9125 4075)(-9250 4075);
WIRE 16 -1 (-9250 4075)(-9250 4025);
WIRE 16 -1 (-9250 4025)(-9125 4025);
WIRE 16 -1 (-9250 4025)(-9250 3975);
WIRE 16 -1 (-9250 3975)(-9125 3975);
WIRE 16 -1 (-9250 3975)(-9250 3925);
WIRE 16 -1 (-9250 3925)(-9125 3925);
WIRE 16 -1 (-9250 3925)(-9250 3875);
WIRE 16 -1 (-9250 3875)(-9125 3875);
WIRE 16 -1 (-9250 3875)(-9250 3825);
WIRE 16 -1 (-9250 3825)(-9125 3825);
WIRE 16 -1 (-9250 3825)(-9250 3775);
WIRE 16 -1 (-9250 3775)(-9125 3775);
WIRE 16 -1 (-9250 3775)(-9250 3725);
WIRE 16 -1 (-9125 3725)(-9250 3725);
WIRE 16 -1 (-9250 3725)(-9250 3675);
WIRE 16 -1 (-9125 3675)(-9250 3675);
WIRE 16 -1 (-9250 3675)(-9250 3625);
WIRE 16 -1 (-9250 3625)(-9125 3625);
WIRE 16 -1 (-9250 3625)(-9250 3575);
WIRE 16 -1 (-9250 3575)(-9125 3575);
WIRE 16 -1 (-9250 3575)(-9250 3525);
WIRE 16 -1 (-9250 3525)(-9125 3525);
WIRE 16 -1 (-9250 3525)(-9250 3475);
WIRE 16 -1 (-9250 3475)(-9125 3475);
WIRE 16 -1 (-9250 3475)(-9250 3425);
WIRE 16 -1 (-9250 3425)(-9125 3425);
WIRE 16 -1 (-9250 3425)(-9250 3375);
WIRE 16 -1 (-9250 3375)(-9125 3375);
WIRE 16 -1 (-9250 3375)(-9250 3325);
WIRE 16 -1 (-9125 3325)(-9250 3325);
WIRE 16 -1 (-9250 3325)(-9250 3275);
WIRE 16 -1 (-9125 3275)(-9250 3275);
WIRE 16 -1 (-9250 3275)(-9250 3225);
WIRE 16 -1 (-9250 3225)(-9125 3225);
WIRE 16 -1 (-9250 3225)(-9250 3175);
WIRE 16 -1 (-9250 3175)(-9125 3175);
WIRE 16 -1 (-9250 3175)(-9250 3125);
WIRE 16 -1 (-9250 3125)(-9125 3125);
WIRE 16 -1 (-9250 3125)(-9250 3075);
WIRE 16 -1 (-9250 3075)(-9125 3075);
WIRE 16 -1 (-9250 3075)(-9250 3025);
WIRE 16 -1 (-9250 3025)(-9125 3025);
WIRE 16 -1 (-9250 3025)(-9250 2975);
WIRE 16 -1 (-9250 2975)(-9125 2975);
WIRE 16 -1 (-9250 2975)(-9250 2925);
WIRE 16 -1 (-9125 2925)(-9250 2925);
WIRE 16 -1 (-9250 2925)(-9250 2875);
WIRE 16 -1 (-9125 2875)(-9250 2875);
WIRE 16 -1 (-9250 2875)(-9250 2825);
WIRE 16 -1 (-9250 2825)(-9125 2825);
WIRE 16 -1 (-9250 2825)(-9250 2775);
WIRE 16 -1 (-9250 2775)(-9125 2775);
WIRE 16 -1 (-9250 2775)(-9250 2725);
WIRE 16 -1 (-9250 2725)(-9125 2725);
WIRE 16 -1 (-9250 2725)(-9250 2675);
WIRE 16 -1 (-9250 2675)(-9125 2675);
WIRE 16 -1 (-9250 2675)(-9250 2625);
WIRE 16 -1 (-9250 2625)(-9125 2625);
WIRE 16 -1 (-9250 2625)(-9250 2575);
WIRE 16 -1 (-9250 2575)(-9125 2575);
WIRE 16 -1 (-9250 2575)(-9250 2525);
WIRE 16 -1 (-9125 2525)(-9250 2525);
WIRE 16 -1 (-9250 2525)(-9250 2475);
WIRE 16 -1 (-9125 2475)(-9250 2475);
WIRE 16 -1 (-9250 2475)(-9250 2425);
WIRE 16 -1 (-9250 2425)(-9125 2425);
WIRE 16 -1 (-9250 2425)(-9250 2375);
WIRE 16 -1 (-9250 2375)(-9125 2375);
WIRE 16 -1 (-9250 2375)(-9250 2325);
WIRE 16 -1 (-9250 2325)(-9125 2325);
WIRE 16 -1 (-9250 2325)(-9250 2275);
WIRE 16 -1 (-9250 2275)(-9125 2275);
WIRE 16 -1 (-9250 2275)(-9250 2225);
WIRE 16 -1 (-9250 2225)(-9125 2225);
WIRE 16 -1 (-9250 2225)(-9250 2175);
WIRE 16 -1 (-9250 2175)(-9125 2175);
WIRE 16 -1 (-9250 2175)(-9250 2125);
WIRE 16 -1 (-9125 2125)(-9250 2125);
WIRE 16 -1 (-9250 2125)(-9250 2075);
WIRE 16 -1 (-9125 2075)(-9250 2075);
WIRE 16 -1 (-9250 2075)(-9250 2025);
WIRE 16 -1 (-9250 2025)(-9125 2025);
WIRE 16 -1 (-9250 2025)(-9250 1975);
WIRE 16 -1 (-9250 1975)(-9125 1975);
WIRE 16 -1 (-9250 1975)(-9250 1925);
WIRE 16 -1 (-9250 1925)(-9125 1925);
WIRE 16 -1 (-9250 1925)(-9250 1875);
WIRE 16 -1 (-9250 1875)(-9125 1875);
WIRE 16 -1 (-9250 1875)(-9250 1825);
WIRE 16 -1 (-9250 1825)(-9125 1825);
WIRE 16 -1 (-9250 1825)(-9250 1775);
WIRE 16 -1 (-9250 1775)(-9125 1775);
WIRE 16 -1 (-9250 1775)(-9250 1725);
WIRE 16 -1 (-9125 1725)(-9250 1725);
WIRE 16 -1 (-9250 1725)(-9250 1675);
WIRE 16 -1 (-9125 1675)(-9250 1675);
WIRE 16 -1 (-9250 1675)(-9250 1625);
WIRE 16 -1 (-9250 1625)(-9125 1625);
WIRE 16 -1 (-9250 1625)(-9250 1575);
WIRE 16 -1 (-9250 1575)(-9125 1575);
WIRE 16 -1 (-9250 1575)(-9250 1525);
WIRE 16 -1 (-9250 1525)(-9125 1525);
WIRE 16 -1 (-9250 1525)(-9250 1475);
WIRE 16 -1 (-9250 1475)(-9125 1475);
WIRE 16 -1 (-9250 1475)(-9250 1425);
WIRE 16 -1 (-9250 1425)(-9125 1425);
WIRE 16 -1 (-9250 1425)(-9250 1375);
WIRE 16 -1 (-9250 1375)(-9125 1375);
WIRE 16 -1 (-9250 1375)(-9250 1325);
WIRE 16 -1 (-9125 1325)(-9250 1325);
WIRE 16 -1 (-9250 1325)(-9250 1275);
WIRE 16 -1 (-9125 1275)(-9250 1275);
WIRE 16 -1 (-9250 1275)(-9250 1225);
WIRE 16 -1 (-9250 1225)(-9125 1225);
WIRE 16 -1 (-9250 1225)(-9250 1175);
WIRE 16 -1 (-9250 1175)(-9125 1175);
WIRE 16 -1 (-9250 1175)(-9250 1125);
WIRE 16 -1 (-9250 1125)(-9125 1125);
WIRE 16 -1 (-9250 1125)(-9250 1075);
WIRE 16 -1 (-9250 1075)(-9125 1075);
WIRE 16 -1 (-9250 1075)(-9250 1025);
WIRE 16 -1 (-9250 1025)(-9125 1025);
WIRE 16 -1 (-9250 1025)(-9250 975);
WIRE 16 -1 (-9250 975)(-9125 975);
WIRE 16 -1 (-9250 975)(-9250 925);
WIRE 16 -1 (-9125 925)(-9250 925);
WIRE 16 -1 (-9250 925)(-9250 875);
WIRE 16 -1 (-9125 875)(-9250 875);
WIRE 16 -1 (-9250 875)(-9250 825);
WIRE 16 -1 (-9125 825)(-9250 825);
WIRE 16 -1 (-9250 825)(-9250 775);
WIRE 16 -1 (-9125 775)(-9250 775);
WIRE 16 -1 (-9250 775)(-9250 725);
WIRE 16 -1 (-9125 725)(-9250 725);
WIRE 16 -1 (-9250 725)(-9250 675);
WIRE 16 -1 (-9125 675)(-9250 675);
WIRE 16 -1 (-9250 675)(-9250 625);
WIRE 16 -1 (-9125 625)(-9250 625);
WIRE 16 -1 (-9250 625)(-9250 575);
WIRE 16 -1 (-9125 575)(-9250 575);
WIRE 16 -1 (-9250 575)(-9250 525);
WIRE 16 -1 (-9250 525)(-9125 525);
WIRE 16 -1 (-9250 525)(-9250 475);
WIRE 16 -1 (-9250 475)(-9125 475);
WIRE 16 -1 (-9250 475)(-9250 425);
WIRE 16 -1 (-6500 6300)(-6375 6300);
WIRE 16 -1 (-6375 6300)(-6375 6250);
WIRE 16 -1 (-6375 6250)(-6375 6200);
WIRE 16 -1 (-6500 6250)(-6375 6250);
WIRE 16 -1 (-6375 6200)(-6375 6150);
WIRE 16 -1 (-6500 6200)(-6375 6200);
WIRE 16 -1 (-6500 6150)(-6375 6150);
WIRE 16 -1 (-6375 6150)(-6375 6100);
WIRE 16 -1 (-6375 6100)(-6375 6050);
WIRE 16 -1 (-6500 6100)(-6375 6100);
WIRE 16 -1 (-6375 6050)(-6375 6000);
WIRE 16 -1 (-6500 6050)(-6375 6050);
WIRE 16 -1 (-6375 6000)(-6375 5950);
WIRE 16 -1 (-6500 6000)(-6375 6000);
WIRE 16 -1 (-6375 5950)(-6375 5900);
WIRE 16 -1 (-6500 5950)(-6375 5950);
WIRE 16 -1 (-6375 5900)(-6375 5850);
WIRE 16 -1 (-6375 5900)(-6500 5900);
WIRE 16 -1 (-6375 5850)(-6375 5800);
WIRE 16 -1 (-6375 5850)(-6500 5850);
WIRE 16 -1 (-6375 5800)(-6375 5750);
WIRE 16 -1 (-6375 5800)(-6500 5800);
WIRE 16 -1 (-6375 5750)(-6375 5700);
WIRE 16 -1 (-6375 5750)(-6500 5750);
WIRE 16 -1 (-6375 5700)(-6375 5650);
WIRE 16 -1 (-6375 5700)(-6500 5700);
WIRE 16 -1 (-6375 5650)(-6500 5650);
WIRE 16 -1 (-6375 5650)(-6375 5600);
WIRE 16 -1 (-6375 5600)(-6375 5550);
WIRE 16 -1 (-6500 5600)(-6375 5600);
WIRE 16 -1 (-6375 5550)(-6375 5500);
WIRE 16 -1 (-6500 5550)(-6375 5550);
WIRE 16 -1 (-6375 5500)(-6375 5450);
WIRE 16 -1 (-6375 5500)(-6500 5500);
WIRE 16 -1 (-6375 5450)(-6375 5400);
WIRE 16 -1 (-6375 5450)(-6500 5450);
WIRE 16 -1 (-6375 5400)(-6375 5350);
WIRE 16 -1 (-6375 5400)(-6500 5400);
WIRE 16 -1 (-6375 5350)(-6375 5300);
WIRE 16 -1 (-6375 5350)(-6500 5350);
WIRE 16 -1 (-6375 5300)(-6375 5250);
WIRE 16 -1 (-6375 5300)(-6500 5300);
WIRE 16 -1 (-6375 5250)(-6375 5200);
WIRE 16 -1 (-6375 5250)(-6500 5250);
WIRE 16 -1 (-6375 5200)(-6375 5150);
WIRE 16 -1 (-6500 5200)(-6375 5200);
WIRE 16 -1 (-6500 5150)(-6375 5150);
WIRE 16 -1 (-6375 5150)(-6375 5100);
WIRE 16 -1 (-6375 5100)(-6375 5050);
WIRE 16 -1 (-6375 5100)(-6500 5100);
WIRE 16 -1 (-6375 5050)(-6375 5000);
WIRE 16 -1 (-6375 5050)(-6500 5050);
WIRE 16 -1 (-6375 5000)(-6375 4950);
WIRE 16 -1 (-6375 5000)(-6500 5000);
WIRE 16 -1 (-6375 4950)(-6375 4900);
WIRE 16 -1 (-6375 4950)(-6500 4950);
WIRE 16 -1 (-6375 4900)(-6375 4850);
WIRE 16 -1 (-6375 4900)(-6500 4900);
WIRE 16 -1 (-6375 4850)(-6375 4800);
WIRE 16 -1 (-6375 4850)(-6500 4850);
WIRE 16 -1 (-6375 4800)(-6375 4750);
WIRE 16 -1 (-6500 4800)(-6375 4800);
WIRE 16 -1 (-6375 4750)(-6375 4700);
WIRE 16 -1 (-6500 4750)(-6375 4750);
WIRE 16 -1 (-6375 4700)(-6375 4650);
WIRE 16 -1 (-6375 4700)(-6500 4700);
WIRE 16 -1 (-6375 4650)(-6500 4650);
WIRE 16 -1 (-6375 4650)(-6375 4600);
WIRE 16 -1 (-6375 4600)(-6375 4550);
WIRE 16 -1 (-6375 4600)(-6500 4600);
WIRE 16 -1 (-6375 4550)(-6375 4500);
WIRE 16 -1 (-6375 4550)(-6500 4550);
WIRE 16 -1 (-6375 4500)(-6375 4450);
WIRE 16 -1 (-6375 4500)(-6500 4500);
WIRE 16 -1 (-6375 4450)(-6375 4400);
WIRE 16 -1 (-6375 4450)(-6500 4450);
WIRE 16 -1 (-6375 4400)(-6375 4350);
WIRE 16 -1 (-6500 4400)(-6375 4400);
WIRE 16 -1 (-6375 4350)(-6375 4300);
WIRE 16 -1 (-6500 4350)(-6375 4350);
WIRE 16 -1 (-6375 4300)(-6375 4250);
WIRE 16 -1 (-6375 4300)(-6500 4300);
WIRE 16 -1 (-6375 4250)(-6375 4200);
WIRE 16 -1 (-6375 4250)(-6500 4250);
WIRE 16 -1 (-6375 4200)(-6375 4150);
WIRE 16 -1 (-6375 4200)(-6500 4200);
WIRE 16 -1 (-6375 4150)(-6375 4100);
WIRE 16 -1 (-6375 4150)(-6500 4150);
WIRE 16 -1 (-6375 4100)(-6500 4100);
WIRE 16 -1 (-6375 4100)(-6375 4050);
WIRE 16 -1 (-6375 4050)(-6375 4000);
WIRE 16 -1 (-6375 4050)(-6500 4050);
WIRE 16 -1 (-6375 4000)(-6375 3950);
WIRE 16 -1 (-6500 4000)(-6375 4000);
WIRE 16 -1 (-6375 3950)(-6375 3900);
WIRE 16 -1 (-6500 3950)(-6375 3950);
WIRE 16 -1 (-6375 3900)(-6375 3850);
WIRE 16 -1 (-6375 3900)(-6500 3900);
WIRE 16 -1 (-6375 3850)(-6375 3800);
WIRE 16 -1 (-6375 3850)(-6500 3850);
WIRE 16 -1 (-6375 3800)(-6375 3750);
WIRE 16 -1 (-6375 3800)(-6500 3800);
WIRE 16 -1 (-6375 3750)(-6375 3700);
WIRE 16 -1 (-6375 3750)(-6500 3750);
WIRE 16 -1 (-6375 3700)(-6375 3650);
WIRE 16 -1 (-6375 3700)(-6500 3700);
WIRE 16 -1 (-6375 3650)(-6375 3600);
WIRE 16 -1 (-6375 3650)(-6500 3650);
WIRE 16 -1 (-6500 3600)(-6375 3600);
WIRE 16 -1 (-6375 3600)(-6375 3550);
WIRE 16 -1 (-6375 3550)(-6375 3500);
WIRE 16 -1 (-6500 3550)(-6375 3550);
WIRE 16 -1 (-6375 3500)(-6375 3450);
WIRE 16 -1 (-6375 3500)(-6500 3500);
WIRE 16 -1 (-6375 3450)(-6375 3400);
WIRE 16 -1 (-6375 3450)(-6500 3450);
WIRE 16 -1 (-6375 3400)(-6375 3350);
WIRE 16 -1 (-6375 3400)(-6500 3400);
WIRE 16 -1 (-6375 3350)(-6375 3300);
WIRE 16 -1 (-6375 3350)(-6500 3350);
WIRE 16 -1 (-6375 3300)(-6375 3250);
WIRE 16 -1 (-6375 3300)(-6500 3300);
WIRE 16 -1 (-6375 3250)(-6375 3200);
WIRE 16 -1 (-6375 3250)(-6500 3250);
WIRE 16 -1 (-6375 3200)(-6375 3150);
WIRE 16 -1 (-6500 3200)(-6375 3200);
WIRE 16 -1 (-6375 3150)(-6375 3100);
WIRE 16 -1 (-6500 3150)(-6375 3150);
WIRE 16 -1 (-6375 3100)(-6500 3100);
WIRE 16 -1 (-6375 3100)(-6375 3050);
WIRE 16 -1 (-6375 3050)(-6375 3000);
WIRE 16 -1 (-6375 3050)(-6500 3050);
WIRE 16 -1 (-6375 3000)(-6375 2950);
WIRE 16 -1 (-6375 3000)(-6500 3000);
WIRE 16 -1 (-6375 2950)(-6375 2900);
WIRE 16 -1 (-6375 2950)(-6500 2950);
WIRE 16 -1 (-6375 2900)(-6375 2850);
WIRE 16 -1 (-6375 2900)(-6500 2900);
WIRE 16 -1 (-6375 2850)(-6375 2800);
WIRE 16 -1 (-6375 2850)(-6500 2850);
WIRE 16 -1 (-6375 2800)(-6375 2750);
WIRE 16 -1 (-6500 2800)(-6375 2800);
WIRE 16 -1 (-6375 2750)(-6375 2700);
WIRE 16 -1 (-6500 2750)(-6375 2750);
WIRE 16 -1 (-6375 2700)(-6375 2650);
WIRE 16 -1 (-6375 2700)(-6500 2700);
WIRE 16 -1 (-6375 2650)(-6375 2600);
WIRE 16 -1 (-6375 2650)(-6500 2650);
WIRE 16 -1 (-6375 2600)(-6500 2600);
WIRE 16 -1 (-6375 2600)(-6375 2550);
WIRE 16 -1 (-6375 2550)(-6375 2500);
WIRE 16 -1 (-6375 2550)(-6500 2550);
WIRE 16 -1 (-6375 2500)(-6375 2450);
WIRE 16 -1 (-6375 2500)(-6500 2500);
WIRE 16 -1 (-6375 2450)(-6375 2400);
WIRE 16 -1 (-6375 2450)(-6500 2450);
WIRE 16 -1 (-6375 2400)(-6375 2350);
WIRE 16 -1 (-6500 2400)(-6375 2400);
WIRE 16 -1 (-6375 2350)(-6375 2300);
WIRE 16 -1 (-6500 2350)(-6375 2350);
WIRE 16 -1 (-6375 2300)(-6375 2250);
WIRE 16 -1 (-6375 2300)(-6500 2300);
WIRE 16 -1 (-6375 2250)(-6375 2200);
WIRE 16 -1 (-6375 2250)(-6500 2250);
WIRE 16 -1 (-6375 2200)(-6375 2150);
WIRE 16 -1 (-6375 2200)(-6500 2200);
WIRE 16 -1 (-6375 2150)(-6375 2100);
WIRE 16 -1 (-6375 2150)(-6500 2150);
WIRE 16 -1 (-6375 2100)(-6375 2050);
WIRE 16 -1 (-6375 2100)(-6500 2100);
WIRE 16 -1 (-6375 2050)(-6500 2050);
WIRE 16 -1 (-6375 2050)(-6375 2000);
WIRE 16 -1 (-6375 2000)(-6375 1950);
WIRE 16 -1 (-6500 2000)(-6375 2000);
WIRE 16 -1 (-6375 1950)(-6375 1900);
WIRE 16 -1 (-6500 1950)(-6375 1950);
WIRE 16 -1 (-6375 1900)(-6375 1850);
WIRE 16 -1 (-6375 1900)(-6500 1900);
WIRE 16 -1 (-6375 1850)(-6375 1800);
WIRE 16 -1 (-6375 1850)(-6500 1850);
WIRE 16 -1 (-6375 1800)(-6375 1750);
WIRE 16 -1 (-6375 1800)(-6500 1800);
WIRE 16 -1 (-6375 1750)(-6375 1700);
WIRE 16 -1 (-6375 1750)(-6500 1750);
WIRE 16 -1 (-6375 1700)(-6375 1650);
WIRE 16 -1 (-6375 1700)(-6500 1700);
WIRE 16 -1 (-6375 1650)(-6375 1600);
WIRE 16 -1 (-6375 1650)(-6500 1650);
WIRE 16 -1 (-6375 1600)(-6375 1550);
WIRE 16 -1 (-6500 1600)(-6375 1600);
WIRE 16 -1 (-6500 1550)(-6375 1550);
WIRE 16 -1 (-6375 1550)(-6375 1500);
WIRE 16 -1 (-6375 1500)(-6375 1450);
WIRE 16 -1 (-6375 1500)(-6500 1500);
WIRE 16 -1 (-6375 1450)(-6375 1400);
WIRE 16 -1 (-6375 1450)(-6500 1450);
WIRE 16 -1 (-6375 1400)(-6375 1350);
WIRE 16 -1 (-6375 1400)(-6500 1400);
WIRE 16 -1 (-6375 1350)(-6375 1300);
WIRE 16 -1 (-6375 1350)(-6500 1350);
WIRE 16 -1 (-6375 1300)(-6375 1250);
WIRE 16 -1 (-6375 1300)(-6500 1300);
WIRE 16 -1 (-6375 1250)(-6375 1200);
WIRE 16 -1 (-6375 1250)(-6500 1250);
WIRE 16 -1 (-6375 1200)(-6375 1150);
WIRE 16 -1 (-6500 1200)(-6375 1200);
WIRE 16 -1 (-6375 1150)(-6375 1100);
WIRE 16 -1 (-6500 1150)(-6375 1150);
WIRE 16 -1 (-6375 1100)(-6375 1050);
WIRE 16 -1 (-6375 1100)(-6500 1100);
WIRE 16 -1 (-6375 1050)(-6500 1050);
WIRE 16 -1 (-6375 1050)(-6375 1000);
WIRE 16 -1 (-6375 1000)(-6375 950);
WIRE 16 -1 (-6375 1000)(-6500 1000);
WIRE 16 -1 (-6375 950)(-6375 900);
WIRE 16 -1 (-6375 950)(-6500 950);
WIRE 16 -1 (-6375 900)(-6375 850);
WIRE 16 -1 (-6375 900)(-6500 900);
WIRE 16 -1 (-6375 850)(-6375 800);
WIRE 16 -1 (-6375 850)(-6500 850);
WIRE 16 -1 (-6375 800)(-6375 750);
WIRE 16 -1 (-6500 800)(-6375 800);
WIRE 16 -1 (-6375 750)(-6375 700);
WIRE 16 -1 (-6500 750)(-6375 750);
WIRE 16 -1 (-6375 700)(-6375 650);
WIRE 16 -1 (-6375 700)(-6500 700);
WIRE 16 -1 (-6375 650)(-6375 600);
WIRE 16 -1 (-6375 650)(-6500 650);
WIRE 16 -1 (-6375 600)(-6375 550);
WIRE 16 -1 (-6375 600)(-6500 600);
WIRE 16 -1 (-6375 550)(-6500 550);
WIRE 16 -1 (-6375 550)(-6375 500);
WIRE 16 -1 (-6375 500)(-6375 475);
WIRE 16 -1 (-6375 500)(-6500 500);
WIRE 16 -1 (-6250 6325)(-6125 6325);
WIRE 16 -1 (-6250 6325)(-6250 6275);
WIRE 16 -1 (-6250 6275)(-6125 6275);
WIRE 16 -1 (-6250 6275)(-6250 6225);
WIRE 16 -1 (-6250 6225)(-6125 6225);
WIRE 16 -1 (-6250 6225)(-6250 6175);
WIRE 16 -1 (-6250 6175)(-6125 6175);
WIRE 16 -1 (-6250 6175)(-6250 6125);
WIRE 16 -1 (-6250 6125)(-6125 6125);
WIRE 16 -1 (-6250 6125)(-6250 6075);
WIRE 16 -1 (-6125 6075)(-6250 6075);
WIRE 16 -1 (-6250 6075)(-6250 6025);
WIRE 16 -1 (-6125 6025)(-6250 6025);
WIRE 16 -1 (-6250 6025)(-6250 5975);
WIRE 16 -1 (-6250 5975)(-6125 5975);
WIRE 16 -1 (-6250 5975)(-6250 5925);
WIRE 16 -1 (-6250 5925)(-6125 5925);
WIRE 16 -1 (-6250 5925)(-6250 5875);
WIRE 16 -1 (-6250 5875)(-6125 5875);
WIRE 16 -1 (-6250 5875)(-6250 5825);
WIRE 16 -1 (-6250 5825)(-6125 5825);
WIRE 16 -1 (-6250 5825)(-6250 5775);
WIRE 16 -1 (-6250 5775)(-6125 5775);
WIRE 16 -1 (-6250 5775)(-6250 5725);
WIRE 16 -1 (-6250 5725)(-6125 5725);
WIRE 16 -1 (-6250 5725)(-6250 5675);
WIRE 16 -1 (-6125 5675)(-6250 5675);
WIRE 16 -1 (-6250 5675)(-6250 5625);
WIRE 16 -1 (-6125 5625)(-6250 5625);
WIRE 16 -1 (-6250 5625)(-6250 5575);
WIRE 16 -1 (-6250 5575)(-6125 5575);
WIRE 16 -1 (-6250 5575)(-6250 5525);
WIRE 16 -1 (-6250 5525)(-6125 5525);
WIRE 16 -1 (-6250 5525)(-6250 5475);
WIRE 16 -1 (-6250 5475)(-6125 5475);
WIRE 16 -1 (-6250 5475)(-6250 5425);
WIRE 16 -1 (-6250 5425)(-6125 5425);
WIRE 16 -1 (-6250 5425)(-6250 5375);
WIRE 16 -1 (-6250 5375)(-6125 5375);
WIRE 16 -1 (-6250 5375)(-6250 5325);
WIRE 16 -1 (-6250 5325)(-6125 5325);
WIRE 16 -1 (-6250 5325)(-6250 5275);
WIRE 16 -1 (-6125 5275)(-6250 5275);
WIRE 16 -1 (-6250 5275)(-6250 5225);
WIRE 16 -1 (-6125 5225)(-6250 5225);
WIRE 16 -1 (-6250 5225)(-6250 5175);
WIRE 16 -1 (-6250 5175)(-6125 5175);
WIRE 16 -1 (-6250 5175)(-6250 5125);
WIRE 16 -1 (-6250 5125)(-6125 5125);
WIRE 16 -1 (-6250 5125)(-6250 5075);
WIRE 16 -1 (-6250 5075)(-6125 5075);
WIRE 16 -1 (-6250 5075)(-6250 5025);
WIRE 16 -1 (-6250 5025)(-6125 5025);
WIRE 16 -1 (-6250 5025)(-6250 4975);
WIRE 16 -1 (-6250 4975)(-6125 4975);
WIRE 16 -1 (-6250 4975)(-6250 4925);
WIRE 16 -1 (-6250 4925)(-6125 4925);
WIRE 16 -1 (-6250 4925)(-6250 4875);
WIRE 16 -1 (-6125 4875)(-6250 4875);
WIRE 16 -1 (-6250 4875)(-6250 4825);
WIRE 16 -1 (-6125 4825)(-6250 4825);
WIRE 16 -1 (-6250 4825)(-6250 4775);
WIRE 16 -1 (-6250 4775)(-6125 4775);
WIRE 16 -1 (-6250 4775)(-6250 4725);
WIRE 16 -1 (-6250 4725)(-6125 4725);
WIRE 16 -1 (-6250 4725)(-6250 4675);
WIRE 16 -1 (-6250 4675)(-6125 4675);
WIRE 16 -1 (-6250 4675)(-6250 4625);
WIRE 16 -1 (-6250 4625)(-6125 4625);
WIRE 16 -1 (-6250 4625)(-6250 4575);
WIRE 16 -1 (-6250 4575)(-6125 4575);
WIRE 16 -1 (-6250 4575)(-6250 4525);
WIRE 16 -1 (-6250 4525)(-6125 4525);
WIRE 16 -1 (-6250 4525)(-6250 4475);
WIRE 16 -1 (-6125 4475)(-6250 4475);
WIRE 16 -1 (-6250 4475)(-6250 4425);
WIRE 16 -1 (-6125 4425)(-6250 4425);
WIRE 16 -1 (-6250 4425)(-6250 4375);
WIRE 16 -1 (-6250 4375)(-6125 4375);
WIRE 16 -1 (-6250 4375)(-6250 4325);
WIRE 16 -1 (-6250 4325)(-6125 4325);
WIRE 16 -1 (-6250 4325)(-6250 4275);
WIRE 16 -1 (-6250 4275)(-6125 4275);
WIRE 16 -1 (-6250 4275)(-6250 4225);
WIRE 16 -1 (-6250 4225)(-6125 4225);
WIRE 16 -1 (-6250 4225)(-6250 4175);
WIRE 16 -1 (-6250 4175)(-6125 4175);
WIRE 16 -1 (-6250 4175)(-6250 4125);
WIRE 16 -1 (-6250 4125)(-6125 4125);
WIRE 16 -1 (-6250 4125)(-6250 4075);
WIRE 16 -1 (-6125 4075)(-6250 4075);
WIRE 16 -1 (-6250 4075)(-6250 4025);
WIRE 16 -1 (-6125 4025)(-6250 4025);
WIRE 16 -1 (-6250 4025)(-6250 3975);
WIRE 16 -1 (-6250 3975)(-6125 3975);
WIRE 16 -1 (-6250 3975)(-6250 3925);
WIRE 16 -1 (-6250 3925)(-6125 3925);
WIRE 16 -1 (-6250 3925)(-6250 3875);
WIRE 16 -1 (-6250 3875)(-6125 3875);
WIRE 16 -1 (-6250 3875)(-6250 3825);
WIRE 16 -1 (-6250 3825)(-6125 3825);
WIRE 16 -1 (-6250 3825)(-6250 3775);
WIRE 16 -1 (-6250 3775)(-6125 3775);
WIRE 16 -1 (-6250 3775)(-6250 3725);
WIRE 16 -1 (-6250 3725)(-6125 3725);
WIRE 16 -1 (-6250 3725)(-6250 3675);
WIRE 16 -1 (-6125 3675)(-6250 3675);
WIRE 16 -1 (-6250 3675)(-6250 3625);
WIRE 16 -1 (-6125 3625)(-6250 3625);
WIRE 16 -1 (-6250 3625)(-6250 3575);
WIRE 16 -1 (-6250 3575)(-6125 3575);
WIRE 16 -1 (-6250 3575)(-6250 3525);
WIRE 16 -1 (-6250 3525)(-6125 3525);
WIRE 16 -1 (-6250 3525)(-6250 3475);
WIRE 16 -1 (-6250 3475)(-6125 3475);
WIRE 16 -1 (-6250 3475)(-6250 3425);
WIRE 16 -1 (-6250 3425)(-6125 3425);
WIRE 16 -1 (-6250 3425)(-6250 3375);
WIRE 16 -1 (-6250 3375)(-6125 3375);
WIRE 16 -1 (-6250 3375)(-6250 3325);
WIRE 16 -1 (-6250 3325)(-6125 3325);
WIRE 16 -1 (-6250 3325)(-6250 3275);
WIRE 16 -1 (-6125 3275)(-6250 3275);
WIRE 16 -1 (-6250 3275)(-6250 3225);
WIRE 16 -1 (-6125 3225)(-6250 3225);
WIRE 16 -1 (-6250 3225)(-6250 3175);
WIRE 16 -1 (-6250 3175)(-6125 3175);
WIRE 16 -1 (-6250 3175)(-6250 3125);
WIRE 16 -1 (-6250 3125)(-6125 3125);
WIRE 16 -1 (-6250 3125)(-6250 3075);
WIRE 16 -1 (-6250 3075)(-6125 3075);
WIRE 16 -1 (-6250 3075)(-6250 3025);
WIRE 16 -1 (-6250 3025)(-6125 3025);
WIRE 16 -1 (-6250 3025)(-6250 2975);
WIRE 16 -1 (-6250 2975)(-6125 2975);
WIRE 16 -1 (-6250 2975)(-6250 2925);
WIRE 16 -1 (-6250 2925)(-6125 2925);
WIRE 16 -1 (-6250 2925)(-6250 2875);
WIRE 16 -1 (-6125 2875)(-6250 2875);
WIRE 16 -1 (-6250 2875)(-6250 2825);
WIRE 16 -1 (-6125 2825)(-6250 2825);
WIRE 16 -1 (-6250 2825)(-6250 2775);
WIRE 16 -1 (-6250 2775)(-6125 2775);
WIRE 16 -1 (-6250 2775)(-6250 2725);
WIRE 16 -1 (-6250 2725)(-6125 2725);
WIRE 16 -1 (-6250 2725)(-6250 2675);
WIRE 16 -1 (-6250 2675)(-6125 2675);
WIRE 16 -1 (-6250 2675)(-6250 2625);
WIRE 16 -1 (-6250 2625)(-6125 2625);
WIRE 16 -1 (-6250 2625)(-6250 2575);
WIRE 16 -1 (-6250 2575)(-6125 2575);
WIRE 16 -1 (-6250 2575)(-6250 2525);
WIRE 16 -1 (-6250 2525)(-6125 2525);
WIRE 16 -1 (-6250 2525)(-6250 2475);
WIRE 16 -1 (-6125 2475)(-6250 2475);
WIRE 16 -1 (-6250 2475)(-6250 2425);
WIRE 16 -1 (-6125 2425)(-6250 2425);
WIRE 16 -1 (-6250 2425)(-6250 2375);
WIRE 16 -1 (-6250 2375)(-6125 2375);
WIRE 16 -1 (-6250 2375)(-6250 2325);
WIRE 16 -1 (-6250 2325)(-6125 2325);
WIRE 16 -1 (-6250 2325)(-6250 2275);
WIRE 16 -1 (-6250 2275)(-6125 2275);
WIRE 16 -1 (-6250 2275)(-6250 2225);
WIRE 16 -1 (-6250 2225)(-6125 2225);
WIRE 16 -1 (-6250 2225)(-6250 2175);
WIRE 16 -1 (-6250 2175)(-6125 2175);
WIRE 16 -1 (-6250 2175)(-6250 2125);
WIRE 16 -1 (-6250 2125)(-6125 2125);
WIRE 16 -1 (-6250 2125)(-6250 2075);
WIRE 16 -1 (-6125 2075)(-6250 2075);
WIRE 16 -1 (-6250 2075)(-6250 2025);
WIRE 16 -1 (-6125 2025)(-6250 2025);
WIRE 16 -1 (-6250 2025)(-6250 1975);
WIRE 16 -1 (-6250 1975)(-6125 1975);
WIRE 16 -1 (-6250 1975)(-6250 1925);
WIRE 16 -1 (-6250 1925)(-6125 1925);
WIRE 16 -1 (-6250 1925)(-6250 1875);
WIRE 16 -1 (-6250 1875)(-6125 1875);
WIRE 16 -1 (-6250 1875)(-6250 1825);
WIRE 16 -1 (-6250 1825)(-6125 1825);
WIRE 16 -1 (-6250 1825)(-6250 1775);
WIRE 16 -1 (-6250 1775)(-6125 1775);
WIRE 16 -1 (-6250 1775)(-6250 1725);
WIRE 16 -1 (-6250 1725)(-6125 1725);
WIRE 16 -1 (-6250 1725)(-6250 1675);
WIRE 16 -1 (-6125 1675)(-6250 1675);
WIRE 16 -1 (-6250 1675)(-6250 1625);
WIRE 16 -1 (-6125 1625)(-6250 1625);
WIRE 16 -1 (-6250 1625)(-6250 1575);
WIRE 16 -1 (-6250 1575)(-6125 1575);
WIRE 16 -1 (-6250 1575)(-6250 1525);
WIRE 16 -1 (-6250 1525)(-6125 1525);
WIRE 16 -1 (-6250 1525)(-6250 1475);
WIRE 16 -1 (-6250 1475)(-6125 1475);
WIRE 16 -1 (-6250 1475)(-6250 1425);
WIRE 16 -1 (-6250 1425)(-6125 1425);
WIRE 16 -1 (-6250 1425)(-6250 1375);
WIRE 16 -1 (-6250 1375)(-6125 1375);
WIRE 16 -1 (-6250 1375)(-6250 1325);
WIRE 16 -1 (-6250 1325)(-6125 1325);
WIRE 16 -1 (-6250 1325)(-6250 1275);
WIRE 16 -1 (-6125 1275)(-6250 1275);
WIRE 16 -1 (-6250 1275)(-6250 1225);
WIRE 16 -1 (-6125 1225)(-6250 1225);
WIRE 16 -1 (-6250 1225)(-6250 1175);
WIRE 16 -1 (-6250 1175)(-6125 1175);
WIRE 16 -1 (-6250 1175)(-6250 1125);
WIRE 16 -1 (-6250 1125)(-6125 1125);
WIRE 16 -1 (-6250 1125)(-6250 1075);
WIRE 16 -1 (-6250 1075)(-6125 1075);
WIRE 16 -1 (-6250 1075)(-6250 1025);
WIRE 16 -1 (-6250 1025)(-6125 1025);
WIRE 16 -1 (-6250 1025)(-6250 975);
WIRE 16 -1 (-6250 975)(-6125 975);
WIRE 16 -1 (-6250 975)(-6250 925);
WIRE 16 -1 (-6250 925)(-6125 925);
WIRE 16 -1 (-6250 925)(-6250 875);
WIRE 16 -1 (-6125 875)(-6250 875);
WIRE 16 -1 (-6250 875)(-6250 825);
WIRE 16 -1 (-6125 825)(-6250 825);
WIRE 16 -1 (-6250 825)(-6250 775);
WIRE 16 -1 (-6125 775)(-6250 775);
WIRE 16 -1 (-6250 775)(-6250 725);
WIRE 16 -1 (-6125 725)(-6250 725);
WIRE 16 -1 (-6250 725)(-6250 675);
WIRE 16 -1 (-6125 675)(-6250 675);
WIRE 16 -1 (-6250 675)(-6250 625);
WIRE 16 -1 (-6125 625)(-6250 625);
WIRE 16 -1 (-6250 625)(-6250 575);
WIRE 16 -1 (-6125 575)(-6250 575);
WIRE 16 -1 (-6250 575)(-6250 525);
WIRE 16 -1 (-6125 525)(-6250 525);
WIRE 16 -1 (-6250 525)(-6250 475);
WIRE 16 -1 (-5025 6325)(-4900 6325);
WIRE 16 -1 (-4900 6325)(-4900 6275);
WIRE 16 -1 (-4900 6275)(-4900 6225);
WIRE 16 -1 (-5025 6275)(-4900 6275);
WIRE 16 -1 (-4900 6225)(-4900 6175);
WIRE 16 -1 (-5025 6225)(-4900 6225);
WIRE 16 -1 (-5025 6175)(-4900 6175);
WIRE 16 -1 (-4900 6175)(-4900 6125);
WIRE 16 -1 (-4900 6125)(-4900 6075);
WIRE 16 -1 (-5025 6125)(-4900 6125);
WIRE 16 -1 (-4900 6075)(-4900 6025);
WIRE 16 -1 (-5025 6075)(-4900 6075);
WIRE 16 -1 (-4900 6025)(-4900 5975);
WIRE 16 -1 (-5025 6025)(-4900 6025);
WIRE 16 -1 (-4900 5975)(-4900 5925);
WIRE 16 -1 (-4900 5975)(-5025 5975);
WIRE 16 -1 (-4900 5925)(-5025 5925);
WIRE 16 -1 (-4900 5925)(-4900 5875);
WIRE 16 -1 (-4900 5875)(-4900 5825);
WIRE 16 -1 (-4900 5875)(-5025 5875);
WIRE 16 -1 (-4900 5825)(-4900 5775);
WIRE 16 -1 (-4900 5825)(-5025 5825);
WIRE 16 -1 (-4900 5775)(-4900 5725);
WIRE 16 -1 (-4900 5775)(-5025 5775);
WIRE 16 -1 (-4900 5725)(-4900 5675);
WIRE 16 -1 (-4900 5725)(-5025 5725);
WIRE 16 -1 (-5025 5675)(-4900 5675);
WIRE 16 -1 (-4900 5675)(-4900 5625);
WIRE 16 -1 (-4900 5625)(-4900 5575);
WIRE 16 -1 (-5025 5625)(-4900 5625);
WIRE 16 -1 (-4900 5575)(-4900 5525);
WIRE 16 -1 (-4900 5575)(-5025 5575);
WIRE 16 -1 (-4900 5525)(-4900 5475);
WIRE 16 -1 (-4900 5525)(-5025 5525);
WIRE 16 -1 (-4900 5475)(-4900 5425);
WIRE 16 -1 (-4900 5475)(-5025 5475);
WIRE 16 -1 (-4900 5425)(-5025 5425);
WIRE 16 -1 (-4900 5425)(-4900 5375);
WIRE 16 -1 (-4900 5375)(-4900 5325);
WIRE 16 -1 (-4900 5375)(-5025 5375);
WIRE 16 -1 (-4900 5325)(-4900 5275);
WIRE 16 -1 (-4900 5325)(-5025 5325);
WIRE 16 -1 (-4900 5275)(-4900 5225);
WIRE 16 -1 (-5025 5275)(-4900 5275);
WIRE 16 -1 (-4900 5225)(-4900 5175);
WIRE 16 -1 (-5025 5225)(-4900 5225);
WIRE 16 -1 (-4900 5175)(-4900 5125);
WIRE 16 -1 (-4900 5175)(-5025 5175);
WIRE 16 -1 (-4900 5125)(-5025 5125);
WIRE 16 -1 (-4900 5125)(-4900 5075);
WIRE 16 -1 (-4900 5075)(-4900 5025);
WIRE 16 -1 (-4900 5075)(-5025 5075);
WIRE 16 -1 (-4900 5025)(-4900 4975);
WIRE 16 -1 (-4900 5025)(-5025 5025);
WIRE 16 -1 (-4900 4975)(-4900 4925);
WIRE 16 -1 (-4900 4975)(-5025 4975);
WIRE 16 -1 (-4900 4925)(-4900 4875);
WIRE 16 -1 (-4900 4925)(-5025 4925);
WIRE 16 -1 (-5025 4875)(-4900 4875);
WIRE 16 -1 (-4900 4875)(-4900 4825);
WIRE 16 -1 (-4900 4825)(-4900 4775);
WIRE 16 -1 (-5025 4825)(-4900 4825);
WIRE 16 -1 (-4900 4775)(-4900 4725);
WIRE 16 -1 (-4900 4775)(-5025 4775);
WIRE 16 -1 (-4900 4725)(-4900 4675);
WIRE 16 -1 (-4900 4725)(-5025 4725);
WIRE 16 -1 (-4900 4675)(-4900 4625);
WIRE 16 -1 (-4900 4675)(-5025 4675);
WIRE 16 -1 (-4900 4625)(-5025 4625);
WIRE 16 -1 (-4900 4625)(-4900 4575);
WIRE 16 -1 (-4900 4575)(-4900 4525);
WIRE 16 -1 (-4900 4575)(-5025 4575);
WIRE 16 -1 (-4900 4525)(-4900 4475);
WIRE 16 -1 (-4900 4525)(-5025 4525);
WIRE 16 -1 (-4900 4475)(-4900 4425);
WIRE 16 -1 (-5025 4475)(-4900 4475);
WIRE 16 -1 (-4900 4425)(-4900 4375);
WIRE 16 -1 (-5025 4425)(-4900 4425);
WIRE 16 -1 (-4900 4375)(-5025 4375);
WIRE 16 -1 (-4900 4375)(-4900 4325);
WIRE 16 -1 (-4900 4325)(-4900 4275);
WIRE 16 -1 (-4900 4325)(-5025 4325);
WIRE 16 -1 (-4900 4275)(-4900 4225);
WIRE 16 -1 (-4900 4275)(-5025 4275);
WIRE 16 -1 (-4900 4225)(-4900 4175);
WIRE 16 -1 (-4900 4225)(-5025 4225);
WIRE 16 -1 (-4900 4175)(-4900 4125);
WIRE 16 -1 (-4900 4175)(-5025 4175);
WIRE 16 -1 (-4900 4125)(-5025 4125);
WIRE 16 -1 (-4900 4125)(-4900 4075);
WIRE 16 -1 (-4900 4075)(-4900 4025);
WIRE 16 -1 (-5025 4075)(-4900 4075);
WIRE 16 -1 (-4900 4025)(-4900 3975);
WIRE 16 -1 (-5025 4025)(-4900 4025);
WIRE 16 -1 (-4900 3975)(-4900 3925);
WIRE 16 -1 (-4900 3975)(-5025 3975);
WIRE 16 -1 (-4900 3925)(-4900 3875);
WIRE 16 -1 (-4900 3925)(-5025 3925);
WIRE 16 -1 (-4900 3875)(-5025 3875);
WIRE 16 -1 (-4900 3875)(-4900 3825);
WIRE 16 -1 (-4900 3825)(-4900 3775);
WIRE 16 -1 (-4900 3825)(-5025 3825);
WIRE 16 -1 (-4900 3775)(-4900 3725);
WIRE 16 -1 (-4900 3775)(-5025 3775);
WIRE 16 -1 (-4900 3725)(-4900 3675);
WIRE 16 -1 (-4900 3725)(-5025 3725);
WIRE 16 -1 (-4900 3675)(-4900 3625);
WIRE 16 -1 (-5025 3675)(-4900 3675);
WIRE 16 -1 (-5025 3625)(-4900 3625);
WIRE 16 -1 (-4900 3625)(-4900 3575);
WIRE 16 -1 (-4900 3575)(-4900 3525);
WIRE 16 -1 (-4900 3575)(-5025 3575);
WIRE 16 -1 (-4900 3525)(-4900 3475);
WIRE 16 -1 (-4900 3525)(-5025 3525);
WIRE 16 -1 (-4900 3475)(-4900 3425);
WIRE 16 -1 (-4900 3475)(-5025 3475);
WIRE 16 -1 (-4900 3425)(-4900 3375);
WIRE 16 -1 (-4900 3425)(-5025 3425);
WIRE 16 -1 (-4900 3375)(-5025 3375);
WIRE 16 -1 (-4900 3375)(-4900 3325);
WIRE 16 -1 (-4900 3325)(-4900 3275);
WIRE 16 -1 (-4900 3325)(-5025 3325);
WIRE 16 -1 (-4900 3275)(-4900 3225);
WIRE 16 -1 (-5025 3275)(-4900 3275);
WIRE 16 -1 (-4900 3225)(-4900 3175);
WIRE 16 -1 (-5025 3225)(-4900 3225);
WIRE 16 -1 (-4900 3175)(-4900 3125);
WIRE 16 -1 (-4900 3175)(-5025 3175);
WIRE 16 -1 (-4900 3125)(-4900 3075);
WIRE 16 -1 (-4900 3125)(-5025 3125);
WIRE 16 -1 (-4900 3075)(-5025 3075);
WIRE 16 -1 (-4900 3075)(-4900 3025);
WIRE 16 -1 (-4900 3025)(-4900 2975);
WIRE 16 -1 (-4900 3025)(-5025 3025);
WIRE 16 -1 (-4900 2975)(-4900 2925);
WIRE 16 -1 (-4900 2975)(-5025 2975);
WIRE 16 -1 (-4900 2925)(-4900 2875);
WIRE 16 -1 (-4900 2925)(-5025 2925);
WIRE 16 -1 (-4900 2875)(-4900 2825);
WIRE 16 -1 (-5025 2875)(-4900 2875);
WIRE 16 -1 (-5025 2825)(-4900 2825);
WIRE 16 -1 (-4900 2825)(-4900 2775);
WIRE 16 -1 (-4900 2775)(-4900 2725);
WIRE 16 -1 (-4900 2775)(-5025 2775);
WIRE 16 -1 (-4900 2725)(-4900 2675);
WIRE 16 -1 (-4900 2725)(-5025 2725);
WIRE 16 -1 (-4900 2675)(-4900 2625);
WIRE 16 -1 (-4900 2675)(-5025 2675);
WIRE 16 -1 (-4900 2625)(-4900 2575);
WIRE 16 -1 (-4900 2625)(-5025 2625);
WIRE 16 -1 (-4900 2575)(-5025 2575);
WIRE 16 -1 (-4900 2575)(-4900 2525);
WIRE 16 -1 (-4900 2525)(-4900 2475);
WIRE 16 -1 (-4900 2525)(-5025 2525);
WIRE 16 -1 (-4900 2475)(-4900 2425);
WIRE 16 -1 (-5025 2475)(-4900 2475);
WIRE 16 -1 (-4900 2425)(-4900 2375);
WIRE 16 -1 (-5025 2425)(-4900 2425);
WIRE 16 -1 (-4900 2375)(-4900 2325);
WIRE 16 -1 (-4900 2375)(-5025 2375);
WIRE 16 -1 (-4900 2325)(-5025 2325);
WIRE 16 -1 (-4900 2325)(-4900 2275);
WIRE 16 -1 (-4900 2275)(-4900 2225);
WIRE 16 -1 (-4900 2275)(-5025 2275);
WIRE 16 -1 (-4900 2225)(-4900 2175);
WIRE 16 -1 (-4900 2225)(-5025 2225);
WIRE 16 -1 (-4900 2175)(-4900 2125);
WIRE 16 -1 (-4900 2175)(-5025 2175);
WIRE 16 -1 (-4900 2125)(-4900 2075);
WIRE 16 -1 (-4900 2125)(-5025 2125);
WIRE 16 -1 (-5025 2075)(-4900 2075);
WIRE 16 -1 (-4900 2075)(-4900 2025);
WIRE 16 -1 (-4900 2025)(-4900 1975);
WIRE 16 -1 (-5025 2025)(-4900 2025);
WIRE 16 -1 (-4900 1975)(-4900 1925);
WIRE 16 -1 (-4900 1975)(-5025 1975);
WIRE 16 -1 (-4900 1925)(-4900 1875);
WIRE 16 -1 (-4900 1925)(-5025 1925);
WIRE 16 -1 (-4900 1875)(-4900 1825);
WIRE 16 -1 (-4900 1875)(-5025 1875);
WIRE 16 -1 (-4900 1825)(-5025 1825);
WIRE 16 -1 (-4900 1825)(-4900 1775);
WIRE 16 -1 (-4900 1775)(-4900 1725);
WIRE 16 -1 (-4900 1775)(-5025 1775);
WIRE 16 -1 (-4900 1725)(-4900 1675);
WIRE 16 -1 (-4900 1725)(-5025 1725);
WIRE 16 -1 (-4900 1675)(-4900 1625);
WIRE 16 -1 (-5025 1675)(-4900 1675);
WIRE 16 -1 (-4900 1625)(-4900 1575);
WIRE 16 -1 (-5025 1625)(-4900 1625);
WIRE 16 -1 (-4900 1575)(-5025 1575);
WIRE 16 -1 (-4900 1575)(-4900 1525);
WIRE 16 -1 (-4900 1525)(-4900 1475);
WIRE 16 -1 (-4900 1525)(-5025 1525);
WIRE 16 -1 (-4900 1475)(-4900 1425);
WIRE 16 -1 (-4900 1475)(-5025 1475);
WIRE 16 -1 (-4900 1425)(-4900 1375);
WIRE 16 -1 (-4900 1425)(-5025 1425);
WIRE 16 -1 (-4900 1375)(-4900 1325);
WIRE 16 -1 (-4900 1375)(-5025 1375);
WIRE 16 -1 (-4900 1325)(-5025 1325);
WIRE 16 -1 (-4900 1325)(-4900 1275);
WIRE 16 -1 (-4900 1275)(-4900 1225);
WIRE 16 -1 (-5025 1275)(-4900 1275);
WIRE 16 -1 (-4900 1225)(-4900 1175);
WIRE 16 -1 (-5025 1225)(-4900 1225);
WIRE 16 -1 (-4900 1175)(-4900 1125);
WIRE 16 -1 (-4900 1175)(-5025 1175);
WIRE 16 -1 (-4900 1125)(-4900 1075);
WIRE 16 -1 (-4900 1125)(-5025 1125);
WIRE 16 -1 (-4900 1075)(-4900 1025);
WIRE 16 -1 (-4900 1075)(-5025 1075);
WIRE 16 -1 (-4900 1025)(-5025 1025);
WIRE 16 -1 (-4900 1025)(-4900 975);
WIRE 16 -1 (-4900 975)(-4900 925);
WIRE 16 -1 (-4900 975)(-5025 975);
WIRE 16 -1 (-4900 925)(-4900 875);
WIRE 16 -1 (-4900 925)(-5025 925);
WIRE 16 -1 (-4900 875)(-4900 825);
WIRE 16 -1 (-5025 875)(-4900 875);
WIRE 16 -1 (-4900 825)(-4900 775);
WIRE 16 -1 (-5025 825)(-4900 825);
WIRE 16 -1 (-4900 775)(-5025 775);
WIRE 16 -1 (-4900 775)(-4900 725);
WIRE 16 -1 (-4900 725)(-4900 675);
WIRE 16 -1 (-4900 725)(-5025 725);
WIRE 16 -1 (-4900 675)(-4900 625);
WIRE 16 -1 (-4900 675)(-5025 675);
WIRE 16 -1 (-4900 625)(-4900 575);
WIRE 16 -1 (-4900 625)(-5025 625);
WIRE 16 -1 (-4900 575)(-4900 550);
WIRE 16 -1 (-4900 575)(-5025 575);
WIRE 16 -1 (-4750 6400)(-4625 6400);
WIRE 16 -1 (-4750 6400)(-4750 6350);
WIRE 16 -1 (-4750 6350)(-4625 6350);
WIRE 16 -1 (-4750 6350)(-4750 6300);
WIRE 16 -1 (-4750 6300)(-4625 6300);
WIRE 16 -1 (-4750 6300)(-4750 6250);
WIRE 16 -1 (-4750 6250)(-4625 6250);
WIRE 16 -1 (-4750 6250)(-4750 6200);
WIRE 16 -1 (-4750 6200)(-4625 6200);
WIRE 16 -1 (-4750 6200)(-4750 6150);
WIRE 16 -1 (-4625 6150)(-4750 6150);
WIRE 16 -1 (-4750 6150)(-4750 6100);
WIRE 16 -1 (-4750 6100)(-4625 6100);
WIRE 16 -1 (-4750 6100)(-4750 6050);
WIRE 16 -1 (-4750 6050)(-4625 6050);
WIRE 16 -1 (-4750 6050)(-4750 6000);
WIRE 16 -1 (-4750 6000)(-4625 6000);
WIRE 16 -1 (-4750 6000)(-4750 5950);
WIRE 16 -1 (-4750 5950)(-4625 5950);
WIRE 16 -1 (-4750 5950)(-4750 5900);
WIRE 16 -1 (-4625 5900)(-4750 5900);
WIRE 16 -1 (-4750 5900)(-4750 5850);
WIRE 16 -1 (-4750 5850)(-4625 5850);
WIRE 16 -1 (-4750 5850)(-4750 5800);
WIRE 16 -1 (-4750 5800)(-4625 5800);
WIRE 16 -1 (-4750 5800)(-4750 5750);
WIRE 16 -1 (-4750 5750)(-4625 5750);
WIRE 16 -1 (-4750 5750)(-4750 5700);
WIRE 16 -1 (-4750 5700)(-4625 5700);
WIRE 16 -1 (-4750 5700)(-4750 5650);
WIRE 16 -1 (-4625 5650)(-4750 5650);
WIRE 16 -1 (-4750 5650)(-4750 5600);
WIRE 16 -1 (-4750 5600)(-4625 5600);
WIRE 16 -1 (-4750 5600)(-4750 5550);
WIRE 16 -1 (-4750 5550)(-4625 5550);
WIRE 16 -1 (-4750 5550)(-4750 5500);
WIRE 16 -1 (-4750 5500)(-4625 5500);
WIRE 16 -1 (-4750 5500)(-4750 5450);
WIRE 16 -1 (-4750 5450)(-4625 5450);
WIRE 16 -1 (-4750 5450)(-4750 5400);
WIRE 16 -1 (-4625 5400)(-4750 5400);
WIRE 16 -1 (-4750 5400)(-4750 5350);
WIRE 16 -1 (-4750 5350)(-4625 5350);
WIRE 16 -1 (-4750 5350)(-4750 5300);
WIRE 16 -1 (-4750 5300)(-4625 5300);
WIRE 16 -1 (-4750 5300)(-4750 5250);
WIRE 16 -1 (-4750 5250)(-4625 5250);
WIRE 16 -1 (-4750 5250)(-4750 5200);
WIRE 16 -1 (-4750 5200)(-4625 5200);
WIRE 16 -1 (-4750 5200)(-4750 5150);
WIRE 16 -1 (-4750 5150)(-4625 5150);
WIRE 16 -1 (-4750 5150)(-4750 5100);
WIRE 16 -1 (-4625 5100)(-4750 5100);
WIRE 16 -1 (-4750 5100)(-4750 5050);
WIRE 16 -1 (-4750 5050)(-4625 5050);
WIRE 16 -1 (-4750 5050)(-4750 5000);
WIRE 16 -1 (-4750 5000)(-4625 5000);
WIRE 16 -1 (-4750 5000)(-4750 4950);
WIRE 16 -1 (-4750 4950)(-4625 4950);
WIRE 16 -1 (-4750 4950)(-4750 4900);
WIRE 16 -1 (-4750 4900)(-4625 4900);
WIRE 16 -1 (-4750 4900)(-4750 4850);
WIRE 16 -1 (-4625 4850)(-4750 4850);
WIRE 16 -1 (-4750 4850)(-4750 4800);
WIRE 16 -1 (-4750 4800)(-4625 4800);
WIRE 16 -1 (-4750 4800)(-4750 4750);
WIRE 16 -1 (-4750 4750)(-4625 4750);
WIRE 16 -1 (-4750 4750)(-4750 4700);
WIRE 16 -1 (-4750 4700)(-4625 4700);
WIRE 16 -1 (-4750 4700)(-4750 4650);
WIRE 16 -1 (-4750 4650)(-4625 4650);
WIRE 16 -1 (-4750 4650)(-4750 4600);
WIRE 16 -1 (-4625 4600)(-4750 4600);
WIRE 16 -1 (-4750 4600)(-4750 4550);
WIRE 16 -1 (-4750 4550)(-4625 4550);
WIRE 16 -1 (-4750 4550)(-4750 4500);
WIRE 16 -1 (-4750 4500)(-4625 4500);
WIRE 16 -1 (-4750 4500)(-4750 4450);
WIRE 16 -1 (-4750 4450)(-4625 4450);
WIRE 16 -1 (-4750 4450)(-4750 4400);
WIRE 16 -1 (-4750 4400)(-4625 4400);
WIRE 16 -1 (-4750 4400)(-4750 4350);
WIRE 16 -1 (-4625 4350)(-4750 4350);
WIRE 16 -1 (-4750 4350)(-4750 4300);
WIRE 16 -1 (-4750 4300)(-4625 4300);
WIRE 16 -1 (-4750 4300)(-4750 4250);
WIRE 16 -1 (-4750 4250)(-4625 4250);
WIRE 16 -1 (-4750 4250)(-4750 4200);
WIRE 16 -1 (-4750 4200)(-4625 4200);
WIRE 16 -1 (-4750 4200)(-4750 4150);
WIRE 16 -1 (-4750 4150)(-4625 4150);
WIRE 16 -1 (-4750 4150)(-4750 4100);
WIRE 16 -1 (-4625 4100)(-4750 4100);
WIRE 16 -1 (-4750 4100)(-4750 4050);
WIRE 16 -1 (-4750 4050)(-4625 4050);
WIRE 16 -1 (-4750 4050)(-4750 4000);
WIRE 16 -1 (-4750 4000)(-4625 4000);
WIRE 16 -1 (-4750 4000)(-4750 3950);
WIRE 16 -1 (-4750 3950)(-4625 3950);
WIRE 16 -1 (-4750 3950)(-4750 3900);
WIRE 16 -1 (-4750 3900)(-4625 3900);
WIRE 16 -1 (-4750 3900)(-4750 3850);
WIRE 16 -1 (-4625 3850)(-4750 3850);
WIRE 16 -1 (-4750 3850)(-4750 3800);
WIRE 16 -1 (-4750 3800)(-4625 3800);
WIRE 16 -1 (-4750 3800)(-4750 3750);
WIRE 16 -1 (-4750 3750)(-4625 3750);
WIRE 16 -1 (-4750 3750)(-4750 3700);
WIRE 16 -1 (-4750 3700)(-4625 3700);
WIRE 16 -1 (-4750 3700)(-4750 3650);
WIRE 16 -1 (-4750 3650)(-4625 3650);
WIRE 16 -1 (-4750 3650)(-4750 3600);
WIRE 16 -1 (-4625 3600)(-4750 3600);
WIRE 16 -1 (-4750 3600)(-4750 3550);
WIRE 16 -1 (-4750 3550)(-4625 3550);
WIRE 16 -1 (-4750 3550)(-4750 3500);
WIRE 16 -1 (-4750 3500)(-4625 3500);
WIRE 16 -1 (-4750 3500)(-4750 3450);
WIRE 16 -1 (-4750 3450)(-4625 3450);
WIRE 16 -1 (-4750 3450)(-4750 3400);
WIRE 16 -1 (-4750 3400)(-4625 3400);
WIRE 16 -1 (-4750 3400)(-4750 3350);
WIRE 16 -1 (-4625 3350)(-4750 3350);
WIRE 16 -1 (-4750 3350)(-4750 3300);
WIRE 16 -1 (-4750 3300)(-4625 3300);
WIRE 16 -1 (-4750 3300)(-4750 3250);
WIRE 16 -1 (-4750 3250)(-4625 3250);
WIRE 16 -1 (-4750 3250)(-4750 3200);
WIRE 16 -1 (-4750 3200)(-4625 3200);
WIRE 16 -1 (-4750 3200)(-4750 3150);
WIRE 16 -1 (-4750 3150)(-4625 3150);
WIRE 16 -1 (-4750 3150)(-4750 3100);
WIRE 16 -1 (-4750 3100)(-4625 3100);
WIRE 16 -1 (-4750 3100)(-4750 3050);
WIRE 16 -1 (-4625 3050)(-4750 3050);
WIRE 16 -1 (-4750 3050)(-4750 3000);
WIRE 16 -1 (-4750 3000)(-4625 3000);
WIRE 16 -1 (-4750 3000)(-4750 2950);
WIRE 16 -1 (-4750 2950)(-4625 2950);
WIRE 16 -1 (-4750 2950)(-4750 2900);
WIRE 16 -1 (-4750 2900)(-4625 2900);
WIRE 16 -1 (-4750 2900)(-4750 2850);
WIRE 16 -1 (-4750 2850)(-4625 2850);
WIRE 16 -1 (-4750 2850)(-4750 2800);
WIRE 16 -1 (-4625 2800)(-4750 2800);
WIRE 16 -1 (-4750 2800)(-4750 2750);
WIRE 16 -1 (-4750 2750)(-4625 2750);
WIRE 16 -1 (-4750 2750)(-4750 2700);
WIRE 16 -1 (-4750 2700)(-4625 2700);
WIRE 16 -1 (-4750 2700)(-4750 2650);
WIRE 16 -1 (-4750 2650)(-4625 2650);
WIRE 16 -1 (-4750 2650)(-4750 2600);
WIRE 16 -1 (-4750 2600)(-4625 2600);
WIRE 16 -1 (-4750 2600)(-4750 2550);
WIRE 16 -1 (-4625 2550)(-4750 2550);
WIRE 16 -1 (-4750 2550)(-4750 2500);
WIRE 16 -1 (-4750 2500)(-4625 2500);
WIRE 16 -1 (-4750 2500)(-4750 2450);
WIRE 16 -1 (-4750 2450)(-4625 2450);
WIRE 16 -1 (-4750 2450)(-4750 2400);
WIRE 16 -1 (-4750 2400)(-4625 2400);
WIRE 16 -1 (-4750 2400)(-4750 2350);
WIRE 16 -1 (-4750 2350)(-4625 2350);
WIRE 16 -1 (-4750 2350)(-4750 2300);
WIRE 16 -1 (-4625 2300)(-4750 2300);
WIRE 16 -1 (-4750 2300)(-4750 2250);
WIRE 16 -1 (-4750 2250)(-4625 2250);
WIRE 16 -1 (-4750 2250)(-4750 2200);
WIRE 16 -1 (-4750 2200)(-4625 2200);
WIRE 16 -1 (-4750 2200)(-4750 2150);
WIRE 16 -1 (-4750 2150)(-4625 2150);
WIRE 16 -1 (-4750 2150)(-4750 2100);
WIRE 16 -1 (-4750 2100)(-4625 2100);
WIRE 16 -1 (-4750 2100)(-4750 2050);
WIRE 16 -1 (-4625 2050)(-4750 2050);
WIRE 16 -1 (-4750 2050)(-4750 2000);
WIRE 16 -1 (-4750 2000)(-4625 2000);
WIRE 16 -1 (-4750 2000)(-4750 1950);
WIRE 16 -1 (-4750 1950)(-4625 1950);
WIRE 16 -1 (-4750 1950)(-4750 1900);
WIRE 16 -1 (-4750 1900)(-4625 1900);
WIRE 16 -1 (-4750 1900)(-4750 1850);
WIRE 16 -1 (-4750 1850)(-4625 1850);
WIRE 16 -1 (-4750 1850)(-4750 1800);
WIRE 16 -1 (-4625 1800)(-4750 1800);
WIRE 16 -1 (-4750 1800)(-4750 1750);
WIRE 16 -1 (-4750 1750)(-4625 1750);
WIRE 16 -1 (-4750 1750)(-4750 1700);
WIRE 16 -1 (-4750 1700)(-4625 1700);
WIRE 16 -1 (-4750 1700)(-4750 1650);
WIRE 16 -1 (-4750 1650)(-4625 1650);
WIRE 16 -1 (-4750 1650)(-4750 1600);
WIRE 16 -1 (-4750 1600)(-4625 1600);
WIRE 16 -1 (-4750 1600)(-4750 1550);
WIRE 16 -1 (-4625 1550)(-4750 1550);
WIRE 16 -1 (-4750 1550)(-4750 1500);
WIRE 16 -1 (-4750 1500)(-4625 1500);
WIRE 16 -1 (-4750 1500)(-4750 1450);
WIRE 16 -1 (-4750 1450)(-4625 1450);
WIRE 16 -1 (-4750 1450)(-4750 1400);
WIRE 16 -1 (-4750 1400)(-4625 1400);
WIRE 16 -1 (-4750 1400)(-4750 1350);
WIRE 16 -1 (-4750 1350)(-4625 1350);
WIRE 16 -1 (-4750 1350)(-4750 1300);
WIRE 16 -1 (-4625 1300)(-4750 1300);
WIRE 16 -1 (-4750 1300)(-4750 1250);
WIRE 16 -1 (-4750 1250)(-4625 1250);
WIRE 16 -1 (-4750 1250)(-4750 1200);
WIRE 16 -1 (-4750 1200)(-4625 1200);
WIRE 16 -1 (-4750 1200)(-4750 1150);
WIRE 16 -1 (-4750 1150)(-4625 1150);
WIRE 16 -1 (-4750 1150)(-4750 1100);
WIRE 16 -1 (-4750 1100)(-4625 1100);
WIRE 16 -1 (-4750 1100)(-4750 1050);
WIRE 16 -1 (-4750 1050)(-4625 1050);
WIRE 16 -1 (-4750 1050)(-4750 1000);
WIRE 16 -1 (-4625 1000)(-4750 1000);
WIRE 16 -1 (-4750 1000)(-4750 950);
WIRE 16 -1 (-4750 950)(-4625 950);
WIRE 16 -1 (-4750 950)(-4750 900);
WIRE 16 -1 (-4750 900)(-4625 900);
WIRE 16 -1 (-4750 900)(-4750 850);
WIRE 16 -1 (-4750 850)(-4625 850);
WIRE 16 -1 (-4750 850)(-4750 800);
WIRE 16 -1 (-4750 800)(-4625 800);
WIRE 16 -1 (-4750 800)(-4750 750);
WIRE 16 -1 (-4625 750)(-4750 750);
WIRE 16 -1 (-4750 750)(-4750 700);
WIRE 16 -1 (-4750 700)(-4625 700);
WIRE 16 -1 (-4750 700)(-4750 650);
WIRE 16 -1 (-4750 650)(-4625 650);
WIRE 16 -1 (-4750 650)(-4750 600);
WIRE 16 -1 (-4750 600)(-4625 600);
WIRE 16 -1 (-4750 600)(-4750 550);
WIRE 16 -1 (-3525 6400)(-3400 6400);
WIRE 16 -1 (-3400 6400)(-3400 6350);
WIRE 16 -1 (-3400 6350)(-3400 6300);
WIRE 16 -1 (-3525 6350)(-3400 6350);
WIRE 16 -1 (-3400 6300)(-3400 6250);
WIRE 16 -1 (-3525 6300)(-3400 6300);
WIRE 16 -1 (-3400 6250)(-3400 6200);
WIRE 16 -1 (-3525 6250)(-3400 6250);
WIRE 16 -1 (-3400 6200)(-3400 6150);
WIRE 16 -1 (-3525 6200)(-3400 6200);
WIRE 16 -1 (-3525 6150)(-3400 6150);
WIRE 16 -1 (-3400 6150)(-3400 6100);
WIRE 16 -1 (-3400 6100)(-3400 6050);
WIRE 16 -1 (-3525 6100)(-3400 6100);
WIRE 16 -1 (-3400 6050)(-3400 6000);
WIRE 16 -1 (-3525 6050)(-3400 6050);
WIRE 16 -1 (-3400 6000)(-3400 5950);
WIRE 16 -1 (-3400 6000)(-3525 6000);
WIRE 16 -1 (-3400 5950)(-3400 5900);
WIRE 16 -1 (-3400 5950)(-3525 5950);
WIRE 16 -1 (-3400 5900)(-3525 5900);
WIRE 16 -1 (-3400 5900)(-3400 5850);
WIRE 16 -1 (-3400 5850)(-3400 5800);
WIRE 16 -1 (-3400 5850)(-3525 5850);
WIRE 16 -1 (-3400 5800)(-3400 5750);
WIRE 16 -1 (-3400 5800)(-3525 5800);
WIRE 16 -1 (-3400 5750)(-3400 5700);
WIRE 16 -1 (-3400 5750)(-3525 5750);
WIRE 16 -1 (-3400 5700)(-3400 5650);
WIRE 16 -1 (-3525 5700)(-3400 5700);
WIRE 16 -1 (-3525 5650)(-3400 5650);
WIRE 16 -1 (-3400 5650)(-3400 5600);
WIRE 16 -1 (-3400 5600)(-3400 5550);
WIRE 16 -1 (-3400 5600)(-3525 5600);
WIRE 16 -1 (-3400 5550)(-3400 5500);
WIRE 16 -1 (-3400 5550)(-3525 5550);
WIRE 16 -1 (-3400 5500)(-3400 5450);
WIRE 16 -1 (-3400 5500)(-3525 5500);
WIRE 16 -1 (-3400 5450)(-3400 5400);
WIRE 16 -1 (-3400 5450)(-3525 5450);
WIRE 16 -1 (-3400 5400)(-3525 5400);
WIRE 16 -1 (-3400 5400)(-3400 5350);
WIRE 16 -1 (-3400 5350)(-3400 5300);
WIRE 16 -1 (-3400 5350)(-3525 5350);
WIRE 16 -1 (-3400 5300)(-3400 5250);
WIRE 16 -1 (-3525 5300)(-3400 5300);
WIRE 16 -1 (-3400 5250)(-3400 5200);
WIRE 16 -1 (-3525 5250)(-3400 5250);
WIRE 16 -1 (-3400 5200)(-3400 5150);
WIRE 16 -1 (-3400 5200)(-3525 5200);
WIRE 16 -1 (-3400 5150)(-3525 5150);
WIRE 16 -1 (-3400 5150)(-3400 5100);
WIRE 16 -1 (-3400 5100)(-3400 5050);
WIRE 16 -1 (-3400 5100)(-3525 5100);
WIRE 16 -1 (-3400 5050)(-3400 5000);
WIRE 16 -1 (-3400 5050)(-3525 5050);
WIRE 16 -1 (-3400 5000)(-3400 4950);
WIRE 16 -1 (-3400 5000)(-3525 5000);
WIRE 16 -1 (-3400 4950)(-3400 4900);
WIRE 16 -1 (-3400 4950)(-3525 4950);
WIRE 16 -1 (-3525 4900)(-3400 4900);
WIRE 16 -1 (-3400 4900)(-3400 4850);
WIRE 16 -1 (-3400 4850)(-3400 4800);
WIRE 16 -1 (-3525 4850)(-3400 4850);
WIRE 16 -1 (-3400 4800)(-3400 4750);
WIRE 16 -1 (-3400 4800)(-3525 4800);
WIRE 16 -1 (-3400 4750)(-3400 4700);
WIRE 16 -1 (-3400 4750)(-3525 4750);
WIRE 16 -1 (-3400 4700)(-3400 4650);
WIRE 16 -1 (-3400 4700)(-3525 4700);
WIRE 16 -1 (-3400 4650)(-3525 4650);
WIRE 16 -1 (-3400 4650)(-3400 4600);
WIRE 16 -1 (-3400 4600)(-3400 4550);
WIRE 16 -1 (-3400 4600)(-3525 4600);
WIRE 16 -1 (-3400 4550)(-3400 4500);
WIRE 16 -1 (-3400 4550)(-3525 4550);
WIRE 16 -1 (-3400 4500)(-3400 4450);
WIRE 16 -1 (-3525 4500)(-3400 4500);
WIRE 16 -1 (-3400 4450)(-3400 4400);
WIRE 16 -1 (-3525 4450)(-3400 4450);
WIRE 16 -1 (-3400 4400)(-3525 4400);
WIRE 16 -1 (-3400 4400)(-3400 4350);
WIRE 16 -1 (-3400 4350)(-3400 4300);
WIRE 16 -1 (-3400 4350)(-3525 4350);
WIRE 16 -1 (-3400 4300)(-3400 4250);
WIRE 16 -1 (-3400 4300)(-3525 4300);
WIRE 16 -1 (-3400 4250)(-3400 4200);
WIRE 16 -1 (-3400 4250)(-3525 4250);
WIRE 16 -1 (-3400 4200)(-3400 4150);
WIRE 16 -1 (-3400 4200)(-3525 4200);
WIRE 16 -1 (-3400 4150)(-3400 4100);
WIRE 16 -1 (-3400 4150)(-3525 4150);
WIRE 16 -1 (-3525 4100)(-3400 4100);
WIRE 16 -1 (-3400 4100)(-3400 4050);
WIRE 16 -1 (-3400 4050)(-3400 4000);
WIRE 16 -1 (-3525 4050)(-3400 4050);
WIRE 16 -1 (-3400 4000)(-3400 3950);
WIRE 16 -1 (-3400 4000)(-3525 4000);
WIRE 16 -1 (-3400 3950)(-3400 3900);
WIRE 16 -1 (-3400 3950)(-3525 3950);
WIRE 16 -1 (-3400 3900)(-3400 3850);
WIRE 16 -1 (-3400 3900)(-3525 3900);
WIRE 16 -1 (-3400 3850)(-3525 3850);
WIRE 16 -1 (-3400 3850)(-3400 3800);
WIRE 16 -1 (-3400 3800)(-3400 3750);
WIRE 16 -1 (-3400 3800)(-3525 3800);
WIRE 16 -1 (-3400 3750)(-3400 3700);
WIRE 16 -1 (-3400 3750)(-3525 3750);
WIRE 16 -1 (-3400 3700)(-3400 3650);
WIRE 16 -1 (-3525 3700)(-3400 3700);
WIRE 16 -1 (-3400 3650)(-3400 3600);
WIRE 16 -1 (-3525 3650)(-3400 3650);
WIRE 16 -1 (-3400 3600)(-3525 3600);
WIRE 16 -1 (-3400 3600)(-3400 3550);
WIRE 16 -1 (-3400 3550)(-3400 3500);
WIRE 16 -1 (-3400 3550)(-3525 3550);
WIRE 16 -1 (-3400 3500)(-3400 3450);
WIRE 16 -1 (-3400 3500)(-3525 3500);
WIRE 16 -1 (-3400 3450)(-3400 3400);
WIRE 16 -1 (-3400 3450)(-3525 3450);
WIRE 16 -1 (-3400 3400)(-3400 3350);
WIRE 16 -1 (-3400 3400)(-3525 3400);
WIRE 16 -1 (-3400 3350)(-3525 3350);
WIRE 16 -1 (-3400 3350)(-3400 3300);
WIRE 16 -1 (-3400 3300)(-3400 3250);
WIRE 16 -1 (-3525 3300)(-3400 3300);
WIRE 16 -1 (-3400 3250)(-3400 3200);
WIRE 16 -1 (-3525 3250)(-3400 3250);
WIRE 16 -1 (-3400 3200)(-3400 3150);
WIRE 16 -1 (-3400 3200)(-3525 3200);
WIRE 16 -1 (-3400 3150)(-3400 3100);
WIRE 16 -1 (-3400 3150)(-3525 3150);
WIRE 16 -1 (-3400 3100)(-3525 3100);
WIRE 16 -1 (-3400 3100)(-3400 3050);
WIRE 16 -1 (-3400 3050)(-3400 3000);
WIRE 16 -1 (-3400 3050)(-3525 3050);
WIRE 16 -1 (-3400 3000)(-3400 2950);
WIRE 16 -1 (-3400 3000)(-3525 3000);
WIRE 16 -1 (-3400 2950)(-3400 2900);
WIRE 16 -1 (-3400 2950)(-3525 2950);
WIRE 16 -1 (-3400 2900)(-3400 2850);
WIRE 16 -1 (-3525 2900)(-3400 2900);
WIRE 16 -1 (-3525 2850)(-3400 2850);
WIRE 16 -1 (-3400 2850)(-3400 2800);
WIRE 16 -1 (-3400 2800)(-3400 2750);
WIRE 16 -1 (-3400 2800)(-3525 2800);
WIRE 16 -1 (-3400 2750)(-3400 2700);
WIRE 16 -1 (-3400 2750)(-3525 2750);
WIRE 16 -1 (-3400 2700)(-3400 2650);
WIRE 16 -1 (-3400 2700)(-3525 2700);
WIRE 16 -1 (-3400 2650)(-3400 2600);
WIRE 16 -1 (-3400 2650)(-3525 2650);
WIRE 16 -1 (-3400 2600)(-3525 2600);
WIRE 16 -1 (-3400 2600)(-3400 2550);
WIRE 16 -1 (-3400 2550)(-3400 2500);
WIRE 16 -1 (-3400 2550)(-3525 2550);
WIRE 16 -1 (-3400 2500)(-3400 2450);
WIRE 16 -1 (-3525 2500)(-3400 2500);
WIRE 16 -1 (-3400 2450)(-3400 2400);
WIRE 16 -1 (-3525 2450)(-3400 2450);
WIRE 16 -1 (-3400 2400)(-3400 2350);
WIRE 16 -1 (-3400 2400)(-3525 2400);
WIRE 16 -1 (-3400 2350)(-3525 2350);
WIRE 16 -1 (-3400 2350)(-3400 2300);
WIRE 16 -1 (-3400 2300)(-3400 2250);
WIRE 16 -1 (-3400 2300)(-3525 2300);
WIRE 16 -1 (-3400 2250)(-3400 2200);
WIRE 16 -1 (-3400 2250)(-3525 2250);
WIRE 16 -1 (-3400 2200)(-3400 2150);
WIRE 16 -1 (-3400 2200)(-3525 2200);
WIRE 16 -1 (-3400 2150)(-3400 2100);
WIRE 16 -1 (-3400 2150)(-3525 2150);
WIRE 16 -1 (-3400 2100)(-3400 2050);
WIRE 16 -1 (-3525 2100)(-3400 2100);
WIRE 16 -1 (-3525 2050)(-3400 2050);
WIRE 16 -1 (-3400 2050)(-3400 2000);
WIRE 16 -1 (-3400 2000)(-3400 1950);
WIRE 16 -1 (-3400 2000)(-3525 2000);
WIRE 16 -1 (-3400 1950)(-3400 1900);
WIRE 16 -1 (-3400 1950)(-3525 1950);
WIRE 16 -1 (-3400 1900)(-3400 1850);
WIRE 16 -1 (-3400 1900)(-3525 1900);
WIRE 16 -1 (-3400 1850)(-3400 1800);
WIRE 16 -1 (-3400 1850)(-3525 1850);
WIRE 16 -1 (-3400 1800)(-3525 1800);
WIRE 16 -1 (-3400 1800)(-3400 1750);
WIRE 16 -1 (-3400 1750)(-3400 1700);
WIRE 16 -1 (-3400 1750)(-3525 1750);
WIRE 16 -1 (-3400 1700)(-3400 1650);
WIRE 16 -1 (-3525 1700)(-3400 1700);
WIRE 16 -1 (-3400 1650)(-3400 1600);
WIRE 16 -1 (-3525 1650)(-3400 1650);
WIRE 16 -1 (-3400 1600)(-3400 1550);
WIRE 16 -1 (-3400 1600)(-3525 1600);
WIRE 16 -1 (-3400 1550)(-3525 1550);
WIRE 16 -1 (-3400 1550)(-3400 1500);
WIRE 16 -1 (-3400 1500)(-3400 1450);
WIRE 16 -1 (-3400 1500)(-3525 1500);
WIRE 16 -1 (-3400 1450)(-3400 1400);
WIRE 16 -1 (-3400 1450)(-3525 1450);
WIRE 16 -1 (-3400 1400)(-3400 1350);
WIRE 16 -1 (-3400 1400)(-3525 1400);
WIRE 16 -1 (-3400 1350)(-3400 1300);
WIRE 16 -1 (-3400 1350)(-3525 1350);
WIRE 16 -1 (-3525 1300)(-3400 1300);
WIRE 16 -1 (-3400 1300)(-3400 1250);
WIRE 16 -1 (-3400 1250)(-3400 1200);
WIRE 16 -1 (-3525 1250)(-3400 1250);
WIRE 16 -1 (-3400 1200)(-3400 1150);
WIRE 16 -1 (-3400 1200)(-3525 1200);
WIRE 16 -1 (-3400 1150)(-3400 1100);
WIRE 16 -1 (-3400 1150)(-3525 1150);
WIRE 16 -1 (-3400 1100)(-3400 1050);
WIRE 16 -1 (-3400 1100)(-3525 1100);
WIRE 16 -1 (-3400 1050)(-3525 1050);
WIRE 16 -1 (-3400 1050)(-3400 1000);
WIRE 16 -1 (-3400 1000)(-3400 950);
WIRE 16 -1 (-3400 1000)(-3525 1000);
WIRE 16 -1 (-3400 950)(-3400 900);
WIRE 16 -1 (-3400 950)(-3525 950);
WIRE 16 -1 (-3400 900)(-3400 850);
WIRE 16 -1 (-3525 900)(-3400 900);
WIRE 16 -1 (-3400 850)(-3400 800);
WIRE 16 -1 (-3525 850)(-3400 850);
WIRE 16 -1 (-3400 800)(-3525 800);
WIRE 16 -1 (-3400 800)(-3400 750);
WIRE 16 -1 (-3400 750)(-3400 700);
WIRE 16 -1 (-3400 750)(-3525 750);
WIRE 16 -1 (-3400 700)(-3400 650);
WIRE 16 -1 (-3400 700)(-3525 700);
WIRE 16 -1 (-3400 650)(-3400 600);
WIRE 16 -1 (-3400 650)(-3525 650);
WIRE 16 -1 (-3400 600)(-3400 575);
WIRE 16 -1 (-3400 600)(-3525 600);
WIRE 16 -1 (-3250 6400)(-3150 6400);
WIRE 16 -1 (-3250 6400)(-3250 6350);
WIRE 16 -1 (-3250 6350)(-3150 6350);
WIRE 16 -1 (-3250 6350)(-3250 6300);
WIRE 16 -1 (-3250 6300)(-3150 6300);
WIRE 16 -1 (-3250 6300)(-3250 6250);
WIRE 16 -1 (-3250 6250)(-3150 6250);
WIRE 16 -1 (-3250 6250)(-3250 6200);
WIRE 16 -1 (-3250 6200)(-3150 6200);
WIRE 16 -1 (-3250 6200)(-3250 6150);
WIRE 16 -1 (-3150 6150)(-3250 6150);
WIRE 16 -1 (-3250 6150)(-3250 6100);
WIRE 16 -1 (-3150 6100)(-3250 6100);
WIRE 16 -1 (-3250 6100)(-3250 6050);
WIRE 16 -1 (-3250 6050)(-3150 6050);
WIRE 16 -1 (-3250 6050)(-3250 6000);
WIRE 16 -1 (-3250 6000)(-3150 6000);
WIRE 16 -1 (-3250 6000)(-3250 5950);
WIRE 16 -1 (-3250 5950)(-3150 5950);
WIRE 16 -1 (-3250 5950)(-3250 5900);
WIRE 16 -1 (-3250 5900)(-3150 5900);
WIRE 16 -1 (-3250 5900)(-3250 5850);
WIRE 16 -1 (-3250 5850)(-3150 5850);
WIRE 16 -1 (-3250 5850)(-3250 5800);
WIRE 16 -1 (-3250 5800)(-3150 5800);
WIRE 16 -1 (-3250 5800)(-3250 5750);
WIRE 16 -1 (-3150 5750)(-3250 5750);
WIRE 16 -1 (-3250 5750)(-3250 5700);
WIRE 16 -1 (-3150 5700)(-3250 5700);
WIRE 16 -1 (-3250 5700)(-3250 5650);
WIRE 16 -1 (-3250 5650)(-3150 5650);
WIRE 16 -1 (-3250 5650)(-3250 5600);
WIRE 16 -1 (-3250 5600)(-3150 5600);
WIRE 16 -1 (-3250 5600)(-3250 5550);
WIRE 16 -1 (-3250 5550)(-3150 5550);
WIRE 16 -1 (-3250 5550)(-3250 5500);
WIRE 16 -1 (-3250 5500)(-3150 5500);
WIRE 16 -1 (-3250 5500)(-3250 5450);
WIRE 16 -1 (-3250 5450)(-3150 5450);
WIRE 16 -1 (-3250 5450)(-3250 5400);
WIRE 16 -1 (-3250 5400)(-3150 5400);
WIRE 16 -1 (-3250 5400)(-3250 5350);
WIRE 16 -1 (-3150 5350)(-3250 5350);
WIRE 16 -1 (-3250 5350)(-3250 5300);
WIRE 16 -1 (-3150 5300)(-3250 5300);
WIRE 16 -1 (-3250 5300)(-3250 5250);
WIRE 16 -1 (-3250 5250)(-3150 5250);
WIRE 16 -1 (-3250 5250)(-3250 5200);
WIRE 16 -1 (-3250 5200)(-3150 5200);
WIRE 16 -1 (-3250 5200)(-3250 5150);
WIRE 16 -1 (-3250 5150)(-3150 5150);
WIRE 16 -1 (-3250 5150)(-3250 5100);
WIRE 16 -1 (-3250 5100)(-3150 5100);
WIRE 16 -1 (-3250 5100)(-3250 5050);
WIRE 16 -1 (-3250 5050)(-3150 5050);
WIRE 16 -1 (-3250 5050)(-3250 5000);
WIRE 16 -1 (-3250 5000)(-3150 5000);
WIRE 16 -1 (-3250 5000)(-3250 4950);
WIRE 16 -1 (-3150 4950)(-3250 4950);
WIRE 16 -1 (-3250 4950)(-3250 4900);
WIRE 16 -1 (-3150 4900)(-3250 4900);
WIRE 16 -1 (-3250 4900)(-3250 4850);
WIRE 16 -1 (-3250 4850)(-3150 4850);
WIRE 16 -1 (-3250 4850)(-3250 4800);
WIRE 16 -1 (-3250 4800)(-3150 4800);
WIRE 16 -1 (-3250 4800)(-3250 4750);
WIRE 16 -1 (-3250 4750)(-3150 4750);
WIRE 16 -1 (-3250 4750)(-3250 4700);
WIRE 16 -1 (-3250 4700)(-3150 4700);
WIRE 16 -1 (-3250 4700)(-3250 4650);
WIRE 16 -1 (-3250 4650)(-3150 4650);
WIRE 16 -1 (-3250 4650)(-3250 4600);
WIRE 16 -1 (-3250 4600)(-3150 4600);
WIRE 16 -1 (-3250 4600)(-3250 4550);
WIRE 16 -1 (-3150 4550)(-3250 4550);
WIRE 16 -1 (-3250 4550)(-3250 4500);
WIRE 16 -1 (-3150 4500)(-3250 4500);
WIRE 16 -1 (-3250 4500)(-3250 4450);
WIRE 16 -1 (-3250 4450)(-3150 4450);
WIRE 16 -1 (-3250 4450)(-3250 4400);
WIRE 16 -1 (-3250 4400)(-3150 4400);
WIRE 16 -1 (-3250 4400)(-3250 4350);
WIRE 16 -1 (-3250 4350)(-3150 4350);
WIRE 16 -1 (-3250 4350)(-3250 4300);
WIRE 16 -1 (-3250 4300)(-3150 4300);
WIRE 16 -1 (-3250 4300)(-3250 4250);
WIRE 16 -1 (-3250 4250)(-3150 4250);
WIRE 16 -1 (-3250 4250)(-3250 4200);
WIRE 16 -1 (-3250 4200)(-3150 4200);
WIRE 16 -1 (-3250 4200)(-3250 4150);
WIRE 16 -1 (-3150 4150)(-3250 4150);
WIRE 16 -1 (-3250 4150)(-3250 4100);
WIRE 16 -1 (-3150 4100)(-3250 4100);
WIRE 16 -1 (-3250 4100)(-3250 4050);
WIRE 16 -1 (-3250 4050)(-3150 4050);
WIRE 16 -1 (-3250 4050)(-3250 4000);
WIRE 16 -1 (-3250 4000)(-3150 4000);
WIRE 16 -1 (-3250 4000)(-3250 3950);
WIRE 16 -1 (-3250 3950)(-3150 3950);
WIRE 16 -1 (-3250 3950)(-3250 3900);
WIRE 16 -1 (-3250 3900)(-3150 3900);
WIRE 16 -1 (-3250 3900)(-3250 3850);
WIRE 16 -1 (-3250 3850)(-3150 3850);
WIRE 16 -1 (-3250 3850)(-3250 3800);
WIRE 16 -1 (-3250 3800)(-3150 3800);
WIRE 16 -1 (-3250 3800)(-3250 3750);
WIRE 16 -1 (-3150 3750)(-3250 3750);
WIRE 16 -1 (-3250 3750)(-3250 3700);
WIRE 16 -1 (-3150 3700)(-3250 3700);
WIRE 16 -1 (-3250 3700)(-3250 3650);
WIRE 16 -1 (-3250 3650)(-3150 3650);
WIRE 16 -1 (-3250 3650)(-3250 3600);
WIRE 16 -1 (-3250 3600)(-3150 3600);
WIRE 16 -1 (-3250 3600)(-3250 3550);
WIRE 16 -1 (-3250 3550)(-3150 3550);
WIRE 16 -1 (-3250 3550)(-3250 3500);
WIRE 16 -1 (-3250 3500)(-3150 3500);
WIRE 16 -1 (-3250 3500)(-3250 3450);
WIRE 16 -1 (-3250 3450)(-3150 3450);
WIRE 16 -1 (-3250 3450)(-3250 3400);
WIRE 16 -1 (-3250 3400)(-3150 3400);
WIRE 16 -1 (-3250 3400)(-3250 3350);
WIRE 16 -1 (-3150 3350)(-3250 3350);
WIRE 16 -1 (-3250 3350)(-3250 3300);
WIRE 16 -1 (-3150 3300)(-3250 3300);
WIRE 16 -1 (-3250 3300)(-3250 3250);
WIRE 16 -1 (-3250 3250)(-3150 3250);
WIRE 16 -1 (-3250 3250)(-3250 3200);
WIRE 16 -1 (-3250 3200)(-3150 3200);
WIRE 16 -1 (-3250 3200)(-3250 3150);
WIRE 16 -1 (-3250 3150)(-3150 3150);
WIRE 16 -1 (-3250 3150)(-3250 3100);
WIRE 16 -1 (-3250 3100)(-3150 3100);
WIRE 16 -1 (-3250 3100)(-3250 3050);
WIRE 16 -1 (-3250 3050)(-3150 3050);
WIRE 16 -1 (-3250 3050)(-3250 3000);
WIRE 16 -1 (-3250 3000)(-3150 3000);
WIRE 16 -1 (-3250 3000)(-3250 2950);
WIRE 16 -1 (-3150 2950)(-3250 2950);
WIRE 16 -1 (-3250 2950)(-3250 2900);
WIRE 16 -1 (-3150 2900)(-3250 2900);
WIRE 16 -1 (-3250 2900)(-3250 2850);
WIRE 16 -1 (-3250 2850)(-3150 2850);
WIRE 16 -1 (-3250 2850)(-3250 2800);
WIRE 16 -1 (-3250 2800)(-3150 2800);
WIRE 16 -1 (-3250 2800)(-3250 2750);
WIRE 16 -1 (-3250 2750)(-3150 2750);
WIRE 16 -1 (-3250 2750)(-3250 2700);
WIRE 16 -1 (-3250 2700)(-3150 2700);
WIRE 16 -1 (-3250 2700)(-3250 2650);
WIRE 16 -1 (-3250 2650)(-3150 2650);
WIRE 16 -1 (-3250 2650)(-3250 2600);
WIRE 16 -1 (-3250 2600)(-3150 2600);
WIRE 16 -1 (-3250 2600)(-3250 2550);
WIRE 16 -1 (-3150 2550)(-3250 2550);
WIRE 16 -1 (-3250 2550)(-3250 2500);
WIRE 16 -1 (-3150 2500)(-3250 2500);
WIRE 16 -1 (-3250 2500)(-3250 2450);
WIRE 16 -1 (-3250 2450)(-3150 2450);
WIRE 16 -1 (-3250 2450)(-3250 2400);
WIRE 16 -1 (-3250 2400)(-3150 2400);
WIRE 16 -1 (-3250 2400)(-3250 2350);
WIRE 16 -1 (-3250 2350)(-3150 2350);
WIRE 16 -1 (-3250 2350)(-3250 2300);
WIRE 16 -1 (-3250 2300)(-3150 2300);
WIRE 16 -1 (-3250 2300)(-3250 2250);
WIRE 16 -1 (-3250 2250)(-3150 2250);
WIRE 16 -1 (-3250 2250)(-3250 2200);
WIRE 16 -1 (-3250 2200)(-3150 2200);
WIRE 16 -1 (-3250 2200)(-3250 2150);
WIRE 16 -1 (-3150 2150)(-3250 2150);
WIRE 16 -1 (-3250 2150)(-3250 2100);
WIRE 16 -1 (-3150 2100)(-3250 2100);
WIRE 16 -1 (-3250 2100)(-3250 2050);
WIRE 16 -1 (-3250 2050)(-3150 2050);
WIRE 16 -1 (-3250 2050)(-3250 2000);
WIRE 16 -1 (-3250 2000)(-3150 2000);
WIRE 16 -1 (-3250 2000)(-3250 1950);
WIRE 16 -1 (-3250 1950)(-3150 1950);
WIRE 16 -1 (-3250 1950)(-3250 1900);
WIRE 16 -1 (-3250 1900)(-3150 1900);
WIRE 16 -1 (-3250 1900)(-3250 1850);
WIRE 16 -1 (-3250 1850)(-3150 1850);
WIRE 16 -1 (-3250 1850)(-3250 1800);
WIRE 16 -1 (-3250 1800)(-3150 1800);
WIRE 16 -1 (-3250 1800)(-3250 1750);
WIRE 16 -1 (-3150 1750)(-3250 1750);
WIRE 16 -1 (-3250 1750)(-3250 1700);
WIRE 16 -1 (-3150 1700)(-3250 1700);
WIRE 16 -1 (-3250 1700)(-3250 1650);
WIRE 16 -1 (-3250 1650)(-3150 1650);
WIRE 16 -1 (-3250 1650)(-3250 1600);
WIRE 16 -1 (-3250 1600)(-3150 1600);
WIRE 16 -1 (-3250 1600)(-3250 1550);
WIRE 16 -1 (-3250 1550)(-3150 1550);
WIRE 16 -1 (-3250 1550)(-3250 1500);
WIRE 16 -1 (-3250 1500)(-3150 1500);
WIRE 16 -1 (-3250 1500)(-3250 1450);
WIRE 16 -1 (-3250 1450)(-3150 1450);
WIRE 16 -1 (-3250 1450)(-3250 1400);
WIRE 16 -1 (-3250 1400)(-3150 1400);
WIRE 16 -1 (-3250 1400)(-3250 1350);
WIRE 16 -1 (-3150 1350)(-3250 1350);
WIRE 16 -1 (-3250 1350)(-3250 1300);
WIRE 16 -1 (-3150 1300)(-3250 1300);
WIRE 16 -1 (-3250 1300)(-3250 1250);
WIRE 16 -1 (-3250 1250)(-3150 1250);
WIRE 16 -1 (-3250 1250)(-3250 1200);
WIRE 16 -1 (-3250 1200)(-3150 1200);
WIRE 16 -1 (-3250 1200)(-3250 1150);
WIRE 16 -1 (-3250 1150)(-3150 1150);
WIRE 16 -1 (-3250 1150)(-3250 1100);
WIRE 16 -1 (-3250 1100)(-3150 1100);
WIRE 16 -1 (-3250 1100)(-3250 1050);
WIRE 16 -1 (-3250 1050)(-3150 1050);
WIRE 16 -1 (-3250 1050)(-3250 1000);
WIRE 16 -1 (-3250 1000)(-3150 1000);
WIRE 16 -1 (-3250 1000)(-3250 950);
WIRE 16 -1 (-3150 950)(-3250 950);
WIRE 16 -1 (-3250 950)(-3250 900);
WIRE 16 -1 (-3150 900)(-3250 900);
WIRE 16 -1 (-3250 900)(-3250 850);
WIRE 16 -1 (-3150 850)(-3250 850);
WIRE 16 -1 (-3250 850)(-3250 800);
WIRE 16 -1 (-3150 800)(-3250 800);
WIRE 16 -1 (-3250 800)(-3250 750);
WIRE 16 -1 (-3150 750)(-3250 750);
WIRE 16 -1 (-3250 750)(-3250 700);
WIRE 16 -1 (-3150 700)(-3250 700);
WIRE 16 -1 (-3250 700)(-3250 650);
WIRE 16 -1 (-3150 650)(-3250 650);
WIRE 16 -1 (-3250 650)(-3250 600);
WIRE 16 -1 (-3150 600)(-3250 600);
WIRE 16 -1 (-3250 600)(-3250 550);
WIRE 16 -1 (-3150 550)(-3250 550);
WIRE 16 -1 (-3250 550)(-3250 500);
WIRE 16 -1 (-1925 6450)(-1925 6400);
WIRE 16 -1 (-1925 6450)(-2050 6450);
WIRE 16 -1 (-1925 6400)(-1925 6350);
WIRE 16 -1 (-1925 6400)(-2050 6400);
WIRE 16 -1 (-1925 6350)(-1925 6300);
WIRE 16 -1 (-2050 6350)(-1925 6350);
WIRE 16 -1 (-1925 6300)(-1925 6250);
WIRE 16 -1 (-2050 6300)(-1925 6300);
WIRE 16 -1 (-1925 6250)(-1925 6200);
WIRE 16 -1 (-2050 6250)(-1925 6250);
WIRE 16 -1 (-1925 6200)(-1925 6150);
WIRE 16 -1 (-2050 6200)(-1925 6200);
WIRE 16 -1 (-1925 6150)(-1925 6100);
WIRE 16 -1 (-2050 6150)(-1925 6150);
WIRE 16 -1 (-1925 6100)(-1925 6050);
WIRE 16 -1 (-2050 6100)(-1925 6100);
WIRE 16 -1 (-1925 6050)(-1925 6000);
WIRE 16 -1 (-2050 6050)(-1925 6050);
WIRE 16 -1 (-1925 6000)(-1925 5950);
WIRE 16 -1 (-2050 6000)(-1925 6000);
WIRE 16 -1 (-1925 5950)(-1925 5900);
WIRE 16 -1 (-1925 5950)(-2050 5950);
WIRE 16 -1 (-1925 5900)(-1925 5850);
WIRE 16 -1 (-1925 5900)(-2050 5900);
WIRE 16 -1 (-1925 5850)(-1925 5800);
WIRE 16 -1 (-1925 5850)(-2050 5850);
WIRE 16 -1 (-1925 5800)(-1925 5750);
WIRE 16 -1 (-1925 5800)(-2050 5800);
WIRE 16 -1 (-1925 5750)(-1925 5700);
WIRE 16 -1 (-1925 5750)(-2050 5750);
WIRE 16 -1 (-1925 5700)(-1925 5650);
WIRE 16 -1 (-1925 5700)(-2050 5700);
WIRE 16 -1 (-1925 5650)(-1925 5600);
WIRE 16 -1 (-2050 5650)(-1925 5650);
WIRE 16 -1 (-1925 5600)(-1925 5550);
WIRE 16 -1 (-2050 5600)(-1925 5600);
WIRE 16 -1 (-1925 5550)(-1925 5500);
WIRE 16 -1 (-1925 5550)(-2050 5550);
WIRE 16 -1 (-1925 5500)(-1925 5450);
WIRE 16 -1 (-1925 5500)(-2050 5500);
WIRE 16 -1 (-1925 5450)(-1925 5400);
WIRE 16 -1 (-1925 5450)(-2050 5450);
WIRE 16 -1 (-1925 5400)(-1925 5350);
WIRE 16 -1 (-1925 5400)(-2050 5400);
WIRE 16 -1 (-1925 5350)(-1925 5300);
WIRE 16 -1 (-1925 5350)(-2050 5350);
WIRE 16 -1 (-1925 5300)(-1925 5250);
WIRE 16 -1 (-1925 5300)(-2050 5300);
WIRE 16 -1 (-1925 5250)(-1925 5200);
WIRE 16 -1 (-2050 5250)(-1925 5250);
WIRE 16 -1 (-1925 5200)(-1925 5150);
WIRE 16 -1 (-2050 5200)(-1925 5200);
WIRE 16 -1 (-1925 5150)(-1925 5100);
WIRE 16 -1 (-1925 5150)(-2050 5150);
WIRE 16 -1 (-1925 5100)(-1925 5050);
WIRE 16 -1 (-1925 5100)(-2050 5100);
WIRE 16 -1 (-1925 5050)(-1925 5000);
WIRE 16 -1 (-1925 5050)(-2050 5050);
WIRE 16 -1 (-1925 5000)(-1925 4950);
WIRE 16 -1 (-1925 5000)(-2050 5000);
WIRE 16 -1 (-1925 4950)(-1925 4900);
WIRE 16 -1 (-1925 4950)(-2050 4950);
WIRE 16 -1 (-1925 4900)(-1925 4850);
WIRE 16 -1 (-1925 4900)(-2050 4900);
WIRE 16 -1 (-1925 4850)(-1925 4800);
WIRE 16 -1 (-2050 4850)(-1925 4850);
WIRE 16 -1 (-1925 4800)(-1925 4750);
WIRE 16 -1 (-2050 4800)(-1925 4800);
WIRE 16 -1 (-1925 4750)(-1925 4700);
WIRE 16 -1 (-1925 4750)(-2050 4750);
WIRE 16 -1 (-1925 4700)(-1925 4650);
WIRE 16 -1 (-1925 4700)(-2050 4700);
WIRE 16 -1 (-1925 4650)(-1925 4600);
WIRE 16 -1 (-1925 4650)(-2050 4650);
WIRE 16 -1 (-1925 4600)(-1925 4550);
WIRE 16 -1 (-1925 4600)(-2050 4600);
WIRE 16 -1 (-1925 4550)(-1925 4500);
WIRE 16 -1 (-1925 4550)(-2050 4550);
WIRE 16 -1 (-1925 4500)(-1925 4450);
WIRE 16 -1 (-1925 4500)(-2050 4500);
WIRE 16 -1 (-1925 4450)(-1925 4400);
WIRE 16 -1 (-2050 4450)(-1925 4450);
WIRE 16 -1 (-1925 4400)(-1925 4350);
WIRE 16 -1 (-2050 4400)(-1925 4400);
WIRE 16 -1 (-1925 4350)(-1925 4300);
WIRE 16 -1 (-1925 4350)(-2050 4350);
WIRE 16 -1 (-1925 4300)(-1925 4250);
WIRE 16 -1 (-1925 4300)(-2050 4300);
WIRE 16 -1 (-1925 4250)(-1925 4200);
WIRE 16 -1 (-1925 4250)(-2050 4250);
WIRE 16 -1 (-1925 4200)(-1925 4150);
WIRE 16 -1 (-1925 4200)(-2050 4200);
WIRE 16 -1 (-1925 4150)(-1925 4100);
WIRE 16 -1 (-1925 4150)(-2050 4150);
WIRE 16 -1 (-1925 4100)(-2050 4100);
WIRE 16 -1 (-1925 4100)(-1925 4050);
WIRE 16 -1 (-1925 4050)(-1925 4000);
WIRE 16 -1 (-2050 4050)(-1925 4050);
WIRE 16 -1 (-1925 4000)(-1925 3950);
WIRE 16 -1 (-2050 4000)(-1925 4000);
WIRE 16 -1 (-1925 3950)(-1925 3900);
WIRE 16 -1 (-1925 3950)(-2050 3950);
WIRE 16 -1 (-1925 3900)(-1925 3850);
WIRE 16 -1 (-1925 3900)(-2050 3900);
WIRE 16 -1 (-1925 3850)(-1925 3800);
WIRE 16 -1 (-1925 3850)(-2050 3850);
WIRE 16 -1 (-1925 3800)(-1925 3750);
WIRE 16 -1 (-1925 3800)(-2050 3800);
WIRE 16 -1 (-1925 3750)(-1925 3700);
WIRE 16 -1 (-1925 3750)(-2050 3750);
WIRE 16 -1 (-1925 3700)(-1925 3650);
WIRE 16 -1 (-1925 3700)(-2050 3700);
WIRE 16 -1 (-1925 3650)(-1925 3600);
WIRE 16 -1 (-2050 3650)(-1925 3650);
WIRE 16 -1 (-1925 3600)(-1925 3550);
WIRE 16 -1 (-2050 3600)(-1925 3600);
WIRE 16 -1 (-1925 3550)(-1925 3500);
WIRE 16 -1 (-1925 3550)(-2050 3550);
WIRE 16 -1 (-1925 3500)(-1925 3450);
WIRE 16 -1 (-1925 3500)(-2050 3500);
WIRE 16 -1 (-1925 3450)(-1925 3400);
WIRE 16 -1 (-1925 3450)(-2050 3450);
WIRE 16 -1 (-1925 3400)(-1925 3350);
WIRE 16 -1 (-1925 3400)(-2050 3400);
WIRE 16 -1 (-1925 3350)(-1925 3300);
WIRE 16 -1 (-1925 3350)(-2050 3350);
WIRE 16 -1 (-1925 3300)(-1925 3250);
WIRE 16 -1 (-1925 3300)(-2050 3300);
WIRE 16 -1 (-1925 3250)(-1925 3200);
WIRE 16 -1 (-2050 3250)(-1925 3250);
WIRE 16 -1 (-1925 3200)(-1925 3150);
WIRE 16 -1 (-2050 3200)(-1925 3200);
WIRE 16 -1 (-1925 3150)(-1925 3100);
WIRE 16 -1 (-1925 3150)(-2050 3150);
WIRE 16 -1 (-1925 3100)(-1925 3050);
WIRE 16 -1 (-1925 3100)(-2050 3100);
WIRE 16 -1 (-1925 3050)(-1925 3000);
WIRE 16 -1 (-1925 3050)(-2050 3050);
WIRE 16 -1 (-1925 3000)(-1925 2950);
WIRE 16 -1 (-1925 3000)(-2050 3000);
WIRE 16 -1 (-1925 2950)(-1925 2900);
WIRE 16 -1 (-1925 2950)(-2050 2950);
WIRE 16 -1 (-1925 2900)(-1925 2850);
WIRE 16 -1 (-1925 2900)(-2050 2900);
WIRE 16 -1 (-1925 2850)(-1925 2800);
WIRE 16 -1 (-2050 2850)(-1925 2850);
WIRE 16 -1 (-1925 2800)(-1925 2750);
WIRE 16 -1 (-2050 2800)(-1925 2800);
WIRE 16 -1 (-1925 2750)(-1925 2700);
WIRE 16 -1 (-1925 2750)(-2050 2750);
WIRE 16 -1 (-1925 2700)(-1925 2650);
WIRE 16 -1 (-1925 2700)(-2050 2700);
WIRE 16 -1 (-1925 2650)(-1925 2600);
WIRE 16 -1 (-1925 2650)(-2050 2650);
WIRE 16 -1 (-1925 2600)(-1925 2550);
WIRE 16 -1 (-1925 2600)(-2050 2600);
WIRE 16 -1 (-1925 2550)(-1925 2500);
WIRE 16 -1 (-1925 2550)(-2050 2550);
WIRE 16 -1 (-1925 2500)(-1925 2450);
WIRE 16 -1 (-1925 2500)(-2050 2500);
WIRE 16 -1 (-1925 2450)(-1925 2400);
WIRE 16 -1 (-2050 2450)(-1925 2450);
WIRE 16 -1 (-1925 2400)(-1925 2350);
WIRE 16 -1 (-2050 2400)(-1925 2400);
WIRE 16 -1 (-1925 2350)(-1925 2300);
WIRE 16 -1 (-1925 2350)(-2050 2350);
WIRE 16 -1 (-1925 2300)(-1925 2250);
WIRE 16 -1 (-1925 2300)(-2050 2300);
WIRE 16 -1 (-1925 2250)(-1925 2200);
WIRE 16 -1 (-1925 2250)(-2050 2250);
WIRE 16 -1 (-1925 2200)(-1925 2150);
WIRE 16 -1 (-1925 2200)(-2050 2200);
WIRE 16 -1 (-1925 2150)(-1925 2100);
WIRE 16 -1 (-1925 2150)(-2050 2150);
WIRE 16 -1 (-1925 2100)(-1925 2050);
WIRE 16 -1 (-1925 2100)(-2050 2100);
WIRE 16 -1 (-1925 2050)(-1925 2000);
WIRE 16 -1 (-2050 2050)(-1925 2050);
WIRE 16 -1 (-1925 2000)(-1925 1950);
WIRE 16 -1 (-2050 2000)(-1925 2000);
WIRE 16 -1 (-1925 1950)(-1925 1900);
WIRE 16 -1 (-1925 1950)(-2050 1950);
WIRE 16 -1 (-1925 1900)(-1925 1850);
WIRE 16 -1 (-1925 1900)(-2050 1900);
WIRE 16 -1 (-1925 1850)(-1925 1800);
WIRE 16 -1 (-1925 1850)(-2050 1850);
WIRE 16 -1 (-1925 1800)(-1925 1750);
WIRE 16 -1 (-1925 1800)(-2050 1800);
WIRE 16 -1 (-1925 1750)(-1925 1700);
WIRE 16 -1 (-1925 1750)(-2050 1750);
WIRE 16 -1 (-1925 1700)(-1925 1650);
WIRE 16 -1 (-1925 1700)(-2050 1700);
WIRE 16 -1 (-1925 1650)(-1925 1600);
WIRE 16 -1 (-2050 1650)(-1925 1650);
WIRE 16 -1 (-1925 1600)(-1925 1550);
WIRE 16 -1 (-2050 1600)(-1925 1600);
WIRE 16 -1 (-1925 1550)(-1925 1500);
WIRE 16 -1 (-1925 1550)(-2050 1550);
WIRE 16 -1 (-1925 1500)(-1925 1450);
WIRE 16 -1 (-1925 1500)(-2050 1500);
WIRE 16 -1 (-1925 1450)(-1925 1400);
WIRE 16 -1 (-1925 1450)(-2050 1450);
WIRE 16 -1 (-1925 1400)(-1925 1350);
WIRE 16 -1 (-1925 1400)(-2050 1400);
WIRE 16 -1 (-1925 1350)(-1925 1300);
WIRE 16 -1 (-1925 1350)(-2050 1350);
WIRE 16 -1 (-1925 1300)(-1925 1250);
WIRE 16 -1 (-1925 1300)(-2050 1300);
WIRE 16 -1 (-1925 1250)(-1925 1200);
WIRE 16 -1 (-2050 1250)(-1925 1250);
WIRE 16 -1 (-1925 1200)(-1925 1150);
WIRE 16 -1 (-2050 1200)(-1925 1200);
WIRE 16 -1 (-1925 1150)(-1925 1100);
WIRE 16 -1 (-1925 1150)(-2050 1150);
WIRE 16 -1 (-1925 1100)(-1925 1050);
WIRE 16 -1 (-1925 1100)(-2050 1100);
WIRE 16 -1 (-1925 1050)(-1925 1000);
WIRE 16 -1 (-1925 1050)(-2050 1050);
WIRE 16 -1 (-1925 1000)(-1925 950);
WIRE 16 -1 (-1925 1000)(-2050 1000);
WIRE 16 -1 (-1925 950)(-1925 900);
WIRE 16 -1 (-1925 950)(-2050 950);
WIRE 16 -1 (-1925 900)(-1925 850);
WIRE 16 -1 (-1925 900)(-2050 900);
WIRE 16 -1 (-1925 850)(-1925 800);
WIRE 16 -1 (-2050 850)(-1925 850);
WIRE 16 -1 (-1925 800)(-1925 750);
WIRE 16 -1 (-2050 800)(-1925 800);
WIRE 16 -1 (-1925 750)(-1925 700);
WIRE 16 -1 (-1925 750)(-2050 750);
WIRE 16 -1 (-1925 700)(-1925 650);
WIRE 16 -1 (-1925 700)(-2050 700);
WIRE 16 -1 (-1925 650)(-1925 600);
WIRE 16 -1 (-1925 650)(-2050 650);
WIRE 16 -1 (-1925 600)(-1925 550);
WIRE 16 -1 (-1925 600)(-2050 600);
WIRE 16 -1 (-1925 550)(-1925 525);
WIRE 16 -1 (-1925 550)(-2050 550);
WIRE 16 -1 (-1625 6450)(-1525 6450);
WIRE 16 -1 (-1625 6450)(-1625 6400);
WIRE 16 -1 (-1625 6400)(-1525 6400);
WIRE 16 -1 (-1625 6400)(-1625 6350);
WIRE 16 -1 (-1625 6350)(-1525 6350);
WIRE 16 -1 (-1625 6350)(-1625 6300);
WIRE 16 -1 (-1625 6300)(-1525 6300);
WIRE 16 -1 (-1625 6300)(-1625 6250);
WIRE 16 -1 (-1625 6250)(-1525 6250);
WIRE 16 -1 (-1625 6250)(-1625 6200);
WIRE 16 -1 (-1525 6200)(-1625 6200);
WIRE 16 -1 (-1625 6200)(-1625 6150);
WIRE 16 -1 (-1525 6150)(-1625 6150);
WIRE 16 -1 (-1625 6150)(-1625 6100);
WIRE 16 -1 (-1625 6100)(-1525 6100);
WIRE 16 -1 (-1625 6100)(-1625 6050);
WIRE 16 -1 (-1625 6050)(-1525 6050);
WIRE 16 -1 (-1625 6050)(-1625 6000);
WIRE 16 -1 (-1625 6000)(-1525 6000);
WIRE 16 -1 (-1625 6000)(-1625 5950);
WIRE 16 -1 (-1625 5950)(-1525 5950);
WIRE 16 -1 (-1625 5950)(-1625 5900);
WIRE 16 -1 (-1625 5900)(-1525 5900);
WIRE 16 -1 (-1625 5900)(-1625 5850);
WIRE 16 -1 (-1625 5850)(-1525 5850);
WIRE 16 -1 (-1625 5850)(-1625 5800);
WIRE 16 -1 (-1525 5800)(-1625 5800);
WIRE 16 -1 (-1625 5800)(-1625 5750);
WIRE 16 -1 (-1525 5750)(-1625 5750);
WIRE 16 -1 (-1625 5750)(-1625 5700);
WIRE 16 -1 (-1625 5700)(-1525 5700);
WIRE 16 -1 (-1625 5700)(-1625 5650);
WIRE 16 -1 (-1625 5650)(-1525 5650);
WIRE 16 -1 (-1625 5650)(-1625 5600);
WIRE 16 -1 (-1625 5600)(-1525 5600);
WIRE 16 -1 (-1625 5600)(-1625 5550);
WIRE 16 -1 (-1625 5550)(-1525 5550);
WIRE 16 -1 (-1625 5550)(-1625 5500);
WIRE 16 -1 (-1625 5500)(-1525 5500);
WIRE 16 -1 (-1625 5500)(-1625 5450);
WIRE 16 -1 (-1625 5450)(-1525 5450);
WIRE 16 -1 (-1625 5450)(-1625 5400);
WIRE 16 -1 (-1525 5400)(-1625 5400);
WIRE 16 -1 (-1625 5400)(-1625 5350);
WIRE 16 -1 (-1525 5350)(-1625 5350);
WIRE 16 -1 (-1625 5350)(-1625 5300);
WIRE 16 -1 (-1625 5300)(-1525 5300);
WIRE 16 -1 (-1625 5300)(-1625 5250);
WIRE 16 -1 (-1625 5250)(-1525 5250);
WIRE 16 -1 (-1625 5250)(-1625 5200);
WIRE 16 -1 (-1625 5200)(-1525 5200);
WIRE 16 -1 (-1625 5200)(-1625 5150);
WIRE 16 -1 (-1625 5150)(-1525 5150);
WIRE 16 -1 (-1625 5150)(-1625 5100);
WIRE 16 -1 (-1625 5100)(-1525 5100);
WIRE 16 -1 (-1625 5100)(-1625 5050);
WIRE 16 -1 (-1625 5050)(-1525 5050);
WIRE 16 -1 (-1625 5050)(-1625 5000);
WIRE 16 -1 (-1525 5000)(-1625 5000);
WIRE 16 -1 (-1625 5000)(-1625 4950);
WIRE 16 -1 (-1525 4950)(-1625 4950);
WIRE 16 -1 (-1625 4950)(-1625 4900);
WIRE 16 -1 (-1625 4900)(-1525 4900);
WIRE 16 -1 (-1625 4900)(-1625 4850);
WIRE 16 -1 (-1625 4850)(-1525 4850);
WIRE 16 -1 (-1625 4850)(-1625 4800);
WIRE 16 -1 (-1625 4800)(-1525 4800);
WIRE 16 -1 (-1625 4800)(-1625 4750);
WIRE 16 -1 (-1625 4750)(-1525 4750);
WIRE 16 -1 (-1625 4750)(-1625 4700);
WIRE 16 -1 (-1625 4700)(-1525 4700);
WIRE 16 -1 (-1625 4700)(-1625 4650);
WIRE 16 -1 (-1625 4650)(-1525 4650);
WIRE 16 -1 (-1625 4650)(-1625 4600);
WIRE 16 -1 (-1525 4600)(-1625 4600);
WIRE 16 -1 (-1625 4600)(-1625 4550);
WIRE 16 -1 (-1525 4550)(-1625 4550);
WIRE 16 -1 (-1625 4550)(-1625 4500);
WIRE 16 -1 (-1625 4500)(-1525 4500);
WIRE 16 -1 (-1625 4500)(-1625 4450);
WIRE 16 -1 (-1625 4450)(-1525 4450);
WIRE 16 -1 (-1625 4450)(-1625 4400);
WIRE 16 -1 (-1625 4400)(-1525 4400);
WIRE 16 -1 (-1625 4400)(-1625 4350);
WIRE 16 -1 (-1625 4350)(-1525 4350);
WIRE 16 -1 (-1625 4350)(-1625 4300);
WIRE 16 -1 (-1625 4300)(-1525 4300);
WIRE 16 -1 (-1625 4300)(-1625 4250);
WIRE 16 -1 (-1625 4250)(-1525 4250);
WIRE 16 -1 (-1625 4250)(-1625 4200);
WIRE 16 -1 (-1525 4200)(-1625 4200);
WIRE 16 -1 (-1625 4200)(-1625 4150);
WIRE 16 -1 (-1525 4150)(-1625 4150);
WIRE 16 -1 (-1625 4150)(-1625 4100);
WIRE 16 -1 (-1625 4100)(-1525 4100);
WIRE 16 -1 (-1625 4100)(-1625 4050);
WIRE 16 -1 (-1625 4050)(-1525 4050);
WIRE 16 -1 (-1625 4050)(-1625 4000);
WIRE 16 -1 (-1625 4000)(-1525 4000);
WIRE 16 -1 (-1625 4000)(-1625 3950);
WIRE 16 -1 (-1625 3950)(-1525 3950);
WIRE 16 -1 (-1625 3950)(-1625 3900);
WIRE 16 -1 (-1625 3900)(-1525 3900);
WIRE 16 -1 (-1625 3900)(-1625 3850);
WIRE 16 -1 (-1625 3850)(-1525 3850);
WIRE 16 -1 (-1625 3850)(-1625 3800);
WIRE 16 -1 (-1525 3800)(-1625 3800);
WIRE 16 -1 (-1625 3800)(-1625 3750);
WIRE 16 -1 (-1525 3750)(-1625 3750);
WIRE 16 -1 (-1625 3750)(-1625 3700);
WIRE 16 -1 (-1625 3700)(-1525 3700);
WIRE 16 -1 (-1625 3700)(-1625 3650);
WIRE 16 -1 (-1625 3650)(-1525 3650);
WIRE 16 -1 (-1625 3650)(-1625 3600);
WIRE 16 -1 (-1625 3600)(-1525 3600);
WIRE 16 -1 (-1625 3600)(-1625 3550);
WIRE 16 -1 (-1625 3550)(-1525 3550);
WIRE 16 -1 (-1625 3550)(-1625 3500);
WIRE 16 -1 (-1625 3500)(-1525 3500);
WIRE 16 -1 (-1625 3500)(-1625 3450);
WIRE 16 -1 (-1625 3450)(-1525 3450);
WIRE 16 -1 (-1625 3450)(-1625 3400);
WIRE 16 -1 (-1525 3400)(-1625 3400);
WIRE 16 -1 (-1625 3400)(-1625 3350);
WIRE 16 -1 (-1525 3350)(-1625 3350);
WIRE 16 -1 (-1625 3350)(-1625 3300);
WIRE 16 -1 (-1625 3300)(-1525 3300);
WIRE 16 -1 (-1625 3300)(-1625 3250);
WIRE 16 -1 (-1625 3250)(-1525 3250);
WIRE 16 -1 (-1625 3250)(-1625 3200);
WIRE 16 -1 (-1625 3200)(-1525 3200);
WIRE 16 -1 (-1625 3200)(-1625 3150);
WIRE 16 -1 (-1625 3150)(-1525 3150);
WIRE 16 -1 (-1625 3150)(-1625 3100);
WIRE 16 -1 (-1625 3100)(-1525 3100);
WIRE 16 -1 (-1625 3100)(-1625 3050);
WIRE 16 -1 (-1625 3050)(-1525 3050);
WIRE 16 -1 (-1625 3050)(-1625 3000);
WIRE 16 -1 (-1525 3000)(-1625 3000);
WIRE 16 -1 (-1625 3000)(-1625 2950);
WIRE 16 -1 (-1525 2950)(-1625 2950);
WIRE 16 -1 (-1625 2950)(-1625 2900);
WIRE 16 -1 (-1625 2900)(-1525 2900);
WIRE 16 -1 (-1625 2900)(-1625 2850);
WIRE 16 -1 (-1625 2850)(-1525 2850);
WIRE 16 -1 (-1625 2850)(-1625 2800);
WIRE 16 -1 (-1625 2800)(-1525 2800);
WIRE 16 -1 (-1625 2800)(-1625 2750);
WIRE 16 -1 (-1625 2750)(-1525 2750);
WIRE 16 -1 (-1625 2750)(-1625 2700);
WIRE 16 -1 (-1625 2700)(-1525 2700);
WIRE 16 -1 (-1625 2700)(-1625 2650);
WIRE 16 -1 (-1625 2650)(-1525 2650);
WIRE 16 -1 (-1625 2650)(-1625 2600);
WIRE 16 -1 (-1525 2600)(-1625 2600);
WIRE 16 -1 (-1625 2600)(-1625 2550);
WIRE 16 -1 (-1525 2550)(-1625 2550);
WIRE 16 -1 (-1625 2550)(-1625 2500);
WIRE 16 -1 (-1625 2500)(-1525 2500);
WIRE 16 -1 (-1625 2500)(-1625 2450);
WIRE 16 -1 (-1625 2450)(-1525 2450);
WIRE 16 -1 (-1625 2450)(-1625 2400);
WIRE 16 -1 (-1625 2400)(-1525 2400);
WIRE 16 -1 (-1625 2400)(-1625 2350);
WIRE 16 -1 (-1625 2350)(-1525 2350);
WIRE 16 -1 (-1625 2350)(-1625 2300);
WIRE 16 -1 (-1625 2300)(-1525 2300);
WIRE 16 -1 (-1625 2300)(-1625 2250);
WIRE 16 -1 (-1625 2250)(-1525 2250);
WIRE 16 -1 (-1625 2250)(-1625 2200);
WIRE 16 -1 (-1525 2200)(-1625 2200);
WIRE 16 -1 (-1625 2200)(-1625 2150);
WIRE 16 -1 (-1525 2150)(-1625 2150);
WIRE 16 -1 (-1625 2150)(-1625 2100);
WIRE 16 -1 (-1625 2100)(-1525 2100);
WIRE 16 -1 (-1625 2100)(-1625 2050);
WIRE 16 -1 (-1625 2050)(-1525 2050);
WIRE 16 -1 (-1625 2050)(-1625 2000);
WIRE 16 -1 (-1625 2000)(-1525 2000);
WIRE 16 -1 (-1625 2000)(-1625 1950);
WIRE 16 -1 (-1625 1950)(-1525 1950);
WIRE 16 -1 (-1625 1950)(-1625 1900);
WIRE 16 -1 (-1625 1900)(-1525 1900);
WIRE 16 -1 (-1625 1900)(-1625 1850);
WIRE 16 -1 (-1625 1850)(-1525 1850);
WIRE 16 -1 (-1625 1850)(-1625 1800);
WIRE 16 -1 (-1525 1800)(-1625 1800);
WIRE 16 -1 (-1625 1800)(-1625 1750);
WIRE 16 -1 (-1525 1750)(-1625 1750);
WIRE 16 -1 (-1625 1750)(-1625 1700);
WIRE 16 -1 (-1625 1700)(-1525 1700);
WIRE 16 -1 (-1625 1700)(-1625 1650);
WIRE 16 -1 (-1625 1650)(-1525 1650);
WIRE 16 -1 (-1625 1650)(-1625 1600);
WIRE 16 -1 (-1625 1600)(-1525 1600);
WIRE 16 -1 (-1625 1600)(-1625 1550);
WIRE 16 -1 (-1625 1550)(-1525 1550);
WIRE 16 -1 (-1625 1550)(-1625 1500);
WIRE 16 -1 (-1625 1500)(-1525 1500);
WIRE 16 -1 (-1625 1500)(-1625 1450);
WIRE 16 -1 (-1625 1450)(-1525 1450);
WIRE 16 -1 (-1625 1450)(-1625 1400);
WIRE 16 -1 (-1525 1400)(-1625 1400);
WIRE 16 -1 (-1625 1400)(-1625 1350);
WIRE 16 -1 (-1525 1350)(-1625 1350);
WIRE 16 -1 (-1625 1350)(-1625 1300);
WIRE 16 -1 (-1625 1300)(-1525 1300);
WIRE 16 -1 (-1625 1300)(-1625 1250);
WIRE 16 -1 (-1625 1250)(-1525 1250);
WIRE 16 -1 (-1625 1250)(-1625 1200);
WIRE 16 -1 (-1625 1200)(-1525 1200);
WIRE 16 -1 (-1625 1200)(-1625 1150);
WIRE 16 -1 (-1625 1150)(-1525 1150);
WIRE 16 -1 (-1625 1150)(-1625 1100);
WIRE 16 -1 (-1625 1100)(-1525 1100);
WIRE 16 -1 (-1625 1100)(-1625 1050);
WIRE 16 -1 (-1625 1050)(-1525 1050);
WIRE 16 -1 (-1625 1050)(-1625 1000);
WIRE 16 -1 (-1525 1000)(-1625 1000);
WIRE 16 -1 (-1625 1000)(-1625 950);
WIRE 16 -1 (-1525 950)(-1625 950);
WIRE 16 -1 (-1625 950)(-1625 900);
WIRE 16 -1 (-1525 900)(-1625 900);
WIRE 16 -1 (-1625 900)(-1625 850);
WIRE 16 -1 (-1525 850)(-1625 850);
WIRE 16 -1 (-1625 850)(-1625 800);
WIRE 16 -1 (-1525 800)(-1625 800);
WIRE 16 -1 (-1625 800)(-1625 750);
WIRE 16 -1 (-1525 750)(-1625 750);
WIRE 16 -1 (-1625 750)(-1625 700);
WIRE 16 -1 (-1525 700)(-1625 700);
WIRE 16 -1 (-1625 700)(-1625 650);
WIRE 16 -1 (-1525 650)(-1625 650);
WIRE 16 -1 (-1625 650)(-1625 600);
WIRE 16 -1 (-1525 600)(-1625 600);
WIRE 16 -1 (-1625 600)(-1625 550);
WIRE 16 -1 (-1525 550)(-1625 550);
WIRE 16 -1 (-1625 550)(-1625 500);
WIRE 16 -1 (-300 6450)(-425 6450);
WIRE 16 -1 (-300 6450)(-300 6400);
WIRE 16 -1 (-300 6400)(-425 6400);
WIRE 16 -1 (-300 6400)(-300 6350);
WIRE 16 -1 (-300 6350)(-300 6300);
WIRE 16 -1 (-425 6350)(-300 6350);
WIRE 16 -1 (-300 6300)(-300 6250);
WIRE 16 -1 (-425 6300)(-300 6300);
WIRE 16 -1 (-300 6250)(-300 6200);
WIRE 16 -1 (-425 6250)(-300 6250);
WIRE 16 -1 (-300 6200)(-300 6150);
WIRE 16 -1 (-425 6200)(-300 6200);
WIRE 16 -1 (-425 6150)(-300 6150);
WIRE 16 -1 (-300 6150)(-300 6100);
WIRE 16 -1 (-300 6100)(-300 6050);
WIRE 16 -1 (-425 6100)(-300 6100);
WIRE 16 -1 (-300 6050)(-300 6000);
WIRE 16 -1 (-425 6050)(-300 6050);
WIRE 16 -1 (-300 6000)(-300 5950);
WIRE 16 -1 (-425 6000)(-300 6000);
WIRE 16 -1 (-300 5950)(-300 5900);
WIRE 16 -1 (-300 5950)(-425 5950);
WIRE 16 -1 (-300 5900)(-425 5900);
WIRE 16 -1 (-300 5900)(-300 5850);
WIRE 16 -1 (-300 5850)(-300 5800);
WIRE 16 -1 (-300 5850)(-425 5850);
WIRE 16 -1 (-300 5800)(-300 5750);
WIRE 16 -1 (-300 5800)(-425 5800);
WIRE 16 -1 (-300 5750)(-300 5700);
WIRE 16 -1 (-300 5750)(-425 5750);
WIRE 16 -1 (-300 5700)(-300 5650);
WIRE 16 -1 (-300 5700)(-425 5700);
WIRE 16 -1 (-425 5650)(-300 5650);
WIRE 16 -1 (-300 5650)(-300 5600);
WIRE 16 -1 (-300 5600)(-300 5550);
WIRE 16 -1 (-425 5600)(-300 5600);
WIRE 16 -1 (-300 5550)(-300 5500);
WIRE 16 -1 (-300 5550)(-425 5550);
WIRE 16 -1 (-300 5500)(-300 5450);
WIRE 16 -1 (-300 5500)(-425 5500);
WIRE 16 -1 (-300 5450)(-300 5400);
WIRE 16 -1 (-300 5450)(-425 5450);
WIRE 16 -1 (-300 5400)(-425 5400);
WIRE 16 -1 (-300 5400)(-300 5350);
WIRE 16 -1 (-300 5350)(-300 5300);
WIRE 16 -1 (-300 5350)(-425 5350);
WIRE 16 -1 (-300 5300)(-300 5250);
WIRE 16 -1 (-300 5300)(-425 5300);
WIRE 16 -1 (-300 5250)(-300 5200);
WIRE 16 -1 (-425 5250)(-300 5250);
WIRE 16 -1 (-300 5200)(-300 5150);
WIRE 16 -1 (-425 5200)(-300 5200);
WIRE 16 -1 (-300 5150)(-425 5150);
WIRE 16 -1 (-300 5150)(-300 5100);
WIRE 16 -1 (-300 5100)(-300 5050);
WIRE 16 -1 (-300 5100)(-425 5100);
WIRE 16 -1 (-300 5050)(-300 5000);
WIRE 16 -1 (-300 5050)(-425 5050);
WIRE 16 -1 (-300 5000)(-300 4950);
WIRE 16 -1 (-300 5000)(-425 5000);
WIRE 16 -1 (-300 4950)(-300 4900);
WIRE 16 -1 (-300 4950)(-425 4950);
WIRE 16 -1 (-300 4900)(-425 4900);
WIRE 16 -1 (-300 4900)(-300 4850);
WIRE 16 -1 (-300 4850)(-300 4800);
WIRE 16 -1 (-425 4850)(-300 4850);
WIRE 16 -1 (-300 4800)(-300 4750);
WIRE 16 -1 (-425 4800)(-300 4800);
WIRE 16 -1 (-300 4750)(-300 4700);
WIRE 16 -1 (-300 4750)(-425 4750);
WIRE 16 -1 (-300 4700)(-300 4650);
WIRE 16 -1 (-300 4700)(-425 4700);
WIRE 16 -1 (-300 4650)(-425 4650);
WIRE 16 -1 (-300 4650)(-300 4600);
WIRE 16 -1 (-300 4600)(-300 4550);
WIRE 16 -1 (-300 4600)(-425 4600);
WIRE 16 -1 (-300 4550)(-300 4500);
WIRE 16 -1 (-300 4550)(-425 4550);
WIRE 16 -1 (-300 4500)(-300 4450);
WIRE 16 -1 (-300 4500)(-425 4500);
WIRE 16 -1 (-300 4450)(-300 4400);
WIRE 16 -1 (-425 4450)(-300 4450);
WIRE 16 -1 (-425 4400)(-300 4400);
WIRE 16 -1 (-300 4400)(-300 4350);
WIRE 16 -1 (-300 4350)(-300 4300);
WIRE 16 -1 (-300 4350)(-425 4350);
WIRE 16 -1 (-300 4300)(-300 4250);
WIRE 16 -1 (-300 4300)(-425 4300);
WIRE 16 -1 (-300 4250)(-300 4200);
WIRE 16 -1 (-300 4250)(-425 4250);
WIRE 16 -1 (-300 4200)(-300 4150);
WIRE 16 -1 (-300 4200)(-425 4200);
WIRE 16 -1 (-300 4150)(-300 4100);
WIRE 16 -1 (-300 4150)(-425 4150);
WIRE 16 -1 (-300 4100)(-425 4100);
WIRE 16 -1 (-300 4100)(-300 4050);
WIRE 16 -1 (-300 4050)(-300 4000);
WIRE 16 -1 (-425 4050)(-300 4050);
WIRE 16 -1 (-300 4000)(-300 3950);
WIRE 16 -1 (-425 4000)(-300 4000);
WIRE 16 -1 (-300 3950)(-300 3900);
WIRE 16 -1 (-300 3950)(-425 3950);
WIRE 16 -1 (-300 3900)(-300 3850);
WIRE 16 -1 (-300 3900)(-425 3900);
WIRE 16 -1 (-300 3850)(-425 3850);
WIRE 16 -1 (-300 3850)(-300 3800);
WIRE 16 -1 (-300 3800)(-300 3750);
WIRE 16 -1 (-300 3800)(-425 3800);
WIRE 16 -1 (-300 3750)(-300 3700);
WIRE 16 -1 (-300 3750)(-425 3750);
WIRE 16 -1 (-300 3700)(-300 3650);
WIRE 16 -1 (-300 3700)(-425 3700);
WIRE 16 -1 (-300 3650)(-300 3600);
WIRE 16 -1 (-425 3650)(-300 3650);
WIRE 16 -1 (-425 3600)(-300 3600);
WIRE 16 -1 (-300 3600)(-300 3550);
WIRE 16 -1 (-300 3550)(-300 3500);
WIRE 16 -1 (-300 3550)(-425 3550);
WIRE 16 -1 (-300 3500)(-300 3450);
WIRE 16 -1 (-300 3500)(-425 3500);
WIRE 16 -1 (-300 3450)(-300 3400);
WIRE 16 -1 (-300 3450)(-425 3450);
WIRE 16 -1 (-300 3400)(-300 3350);
WIRE 16 -1 (-300 3400)(-425 3400);
WIRE 16 -1 (-300 3350)(-425 3350);
WIRE 16 -1 (-300 3350)(-300 3300);
WIRE 16 -1 (-300 3300)(-300 3250);
WIRE 16 -1 (-300 3300)(-425 3300);
WIRE 16 -1 (-300 3250)(-300 3200);
WIRE 16 -1 (-425 3250)(-300 3250);
WIRE 16 -1 (-300 3200)(-300 3150);
WIRE 16 -1 (-425 3200)(-300 3200);
WIRE 16 -1 (-300 3150)(-300 3100);
WIRE 16 -1 (-300 3150)(-425 3150);
WIRE 16 -1 (-300 3100)(-425 3100);
WIRE 16 -1 (-300 3100)(-300 3050);
WIRE 16 -1 (-300 3050)(-300 3000);
WIRE 16 -1 (-300 3050)(-425 3050);
WIRE 16 -1 (-300 3000)(-300 2950);
WIRE 16 -1 (-300 3000)(-425 3000);
WIRE 16 -1 (-300 2950)(-300 2900);
WIRE 16 -1 (-300 2950)(-425 2950);
WIRE 16 -1 (-300 2900)(-300 2850);
WIRE 16 -1 (-300 2900)(-425 2900);
WIRE 16 -1 (-425 2850)(-300 2850);
WIRE 16 -1 (-300 2850)(-300 2800);
WIRE 16 -1 (-300 2800)(-300 2750);
WIRE 16 -1 (-425 2800)(-300 2800);
WIRE 16 -1 (-300 2750)(-300 2700);
WIRE 16 -1 (-300 2750)(-425 2750);
WIRE 16 -1 (-300 2700)(-300 2650);
WIRE 16 -1 (-300 2700)(-425 2700);
WIRE 16 -1 (-300 2650)(-300 2600);
WIRE 16 -1 (-300 2650)(-425 2650);
WIRE 16 -1 (-300 2600)(-425 2600);
WIRE 16 -1 (-300 2600)(-300 2550);
WIRE 16 -1 (-300 2550)(-300 2500);
WIRE 16 -1 (-300 2550)(-425 2550);
WIRE 16 -1 (-300 2500)(-300 2450);
WIRE 16 -1 (-300 2500)(-425 2500);
WIRE 16 -1 (-300 2450)(-300 2400);
WIRE 16 -1 (-425 2450)(-300 2450);
WIRE 16 -1 (-300 2400)(-300 2350);
WIRE 16 -1 (-425 2400)(-300 2400);
WIRE 16 -1 (-300 2350)(-425 2350);
WIRE 16 -1 (-300 2350)(-300 2300);
WIRE 16 -1 (-300 2300)(-300 2250);
WIRE 16 -1 (-300 2300)(-425 2300);
WIRE 16 -1 (-300 2250)(-300 2200);
WIRE 16 -1 (-300 2250)(-425 2250);
WIRE 16 -1 (-300 2200)(-300 2150);
WIRE 16 -1 (-300 2200)(-425 2200);
WIRE 16 -1 (-300 2150)(-300 2100);
WIRE 16 -1 (-300 2150)(-425 2150);
WIRE 16 -1 (-300 2100)(-300 2050);
WIRE 16 -1 (-300 2100)(-425 2100);
WIRE 16 -1 (-425 2050)(-300 2050);
WIRE 16 -1 (-300 2050)(-300 2000);
WIRE 16 -1 (-300 2000)(-300 1950);
WIRE 16 -1 (-425 2000)(-300 2000);
WIRE 16 -1 (-300 1950)(-300 1900);
WIRE 16 -1 (-300 1950)(-425 1950);
WIRE 16 -1 (-300 1900)(-300 1850);
WIRE 16 -1 (-300 1900)(-425 1900);
WIRE 16 -1 (-300 1850)(-300 1800);
WIRE 16 -1 (-300 1850)(-425 1850);
WIRE 16 -1 (-300 1800)(-425 1800);
WIRE 16 -1 (-300 1800)(-300 1750);
WIRE 16 -1 (-300 1750)(-300 1700);
WIRE 16 -1 (-300 1750)(-425 1750);
WIRE 16 -1 (-300 1700)(-300 1650);
WIRE 16 -1 (-300 1700)(-425 1700);
WIRE 16 -1 (-300 1650)(-300 1600);
WIRE 16 -1 (-425 1650)(-300 1650);
WIRE 16 -1 (-300 1600)(-300 1550);
WIRE 16 -1 (-425 1600)(-300 1600);
WIRE 16 -1 (-300 1550)(-425 1550);
WIRE 16 -1 (-300 1550)(-300 1500);
WIRE 16 -1 (-300 1500)(-300 1450);
WIRE 16 -1 (-300 1500)(-425 1500);
WIRE 16 -1 (-300 1450)(-300 1400);
WIRE 16 -1 (-300 1450)(-425 1450);
WIRE 16 -1 (-300 1400)(-300 1350);
WIRE 16 -1 (-300 1400)(-425 1400);
WIRE 16 -1 (-300 1350)(-300 1300);
WIRE 16 -1 (-300 1350)(-425 1350);
WIRE 16 -1 (-300 1300)(-425 1300);
WIRE 16 -1 (-300 1300)(-300 1250);
WIRE 16 -1 (-300 1250)(-300 1200);
WIRE 16 -1 (-425 1250)(-300 1250);
WIRE 16 -1 (-300 1200)(-300 1150);
WIRE 16 -1 (-425 1200)(-300 1200);
WIRE 16 -1 (-300 1150)(-300 1100);
WIRE 16 -1 (-300 1150)(-425 1150);
WIRE 16 -1 (-300 1100)(-300 1050);
WIRE 16 -1 (-300 1100)(-425 1100);
WIRE 16 -1 (-300 1050)(-425 1050);
WIRE 16 -1 (-300 1050)(-300 1000);
WIRE 16 -1 (-300 1000)(-300 950);
WIRE 16 -1 (-300 1000)(-425 1000);
WIRE 16 -1 (-300 950)(-300 900);
WIRE 16 -1 (-300 950)(-425 950);
WIRE 16 -1 (-300 900)(-300 850);
WIRE 16 -1 (-300 900)(-425 900);
WIRE 16 -1 (-300 850)(-300 800);
WIRE 16 -1 (-425 850)(-300 850);
WIRE 16 -1 (-425 800)(-300 800);
WIRE 16 -1 (-300 800)(-300 750);
WIRE 16 -1 (-300 750)(-300 700);
WIRE 16 -1 (-300 750)(-425 750);
WIRE 16 -1 (-300 700)(-300 650);
WIRE 16 -1 (-300 700)(-425 700);
WIRE 16 -1 (-300 650)(-300 600);
WIRE 16 -1 (-300 650)(-425 650);
WIRE 16 -1 (-300 600)(-300 550);
WIRE 16 -1 (-300 600)(-425 600);
WIRE 16 -1 (-300 550)(-300 525);
WIRE 16 -1 (-300 550)(-425 550);
DOT 1 (-9250 475);
DOT 1 (-9250 525);
DOT 1 (-9250 625);
DOT 1 (-9250 575);
DOT 1 (-9250 775);
DOT 1 (-9250 725);
DOT 1 (-9250 825);
DOT 1 (-9250 875);
DOT 1 (-9250 925);
DOT 1 (-9250 1025);
DOT 1 (-9250 975);
DOT 1 (-9250 1175);
DOT 1 (-9250 1125);
DOT 1 (-9250 1075);
DOT 1 (-9250 1225);
DOT 1 (-9250 1275);
DOT 1 (-9250 1425);
DOT 1 (-9250 1375);
DOT 1 (-9250 1325);
DOT 1 (-9250 1525);
DOT 1 (-9250 1475);
DOT 1 (-9250 1675);
DOT 1 (-9250 1625);
DOT 1 (-9250 1575);
DOT 1 (-9250 1725);
DOT 1 (-9250 1775);
DOT 1 (-9250 1825);
DOT 1 (-9250 1925);
DOT 1 (-9250 1875);
DOT 1 (-9250 1975);
DOT 1 (-9250 2025);
DOT 1 (-9250 2075);
DOT 1 (-9250 2175);
DOT 1 (-9250 2125);
DOT 1 (-9250 2325);
DOT 1 (-9250 2275);
DOT 1 (-9250 2225);
DOT 1 (-9250 2375);
DOT 1 (-9250 2425);
DOT 1 (-9250 2575);
DOT 1 (-9250 2525);
DOT 1 (-9250 2475);
DOT 1 (-9250 2675);
DOT 1 (-9250 2625);
DOT 1 (-9250 2725);
DOT 1 (-9250 2825);
DOT 1 (-9250 2775);
DOT 1 (-9250 2875);
DOT 1 (-9250 2925);
DOT 1 (-9250 2975);
DOT 1 (-9250 3075);
DOT 1 (-9250 3025);
DOT 1 (-9250 3175);
DOT 1 (-9250 3125);
DOT 1 (-9250 3225);
DOT 1 (-9250 3275);
DOT 1 (-9250 3325);
DOT 1 (-9250 3475);
DOT 1 (-9250 3425);
DOT 1 (-9250 3375);
DOT 1 (-9250 3575);
DOT 1 (-9250 3525);
DOT 1 (-9250 3725);
DOT 1 (-9250 3675);
DOT 1 (-9250 3625);
DOT 1 (-9250 3775);
DOT 1 (-9250 3825);
DOT 1 (-9250 3875);
DOT 1 (-9250 3975);
DOT 1 (-9250 3925);
DOT 1 (-9250 4075);
DOT 1 (-9250 4025);
DOT 1 (-9250 4125);
DOT 1 (-9250 4225);
DOT 1 (-9250 4175);
DOT 1 (-9250 4375);
DOT 1 (-9250 4325);
DOT 1 (-9250 4275);
DOT 1 (-9250 4425);
DOT 1 (-9250 4475);
DOT 1 (-9250 4625);
DOT 1 (-9250 4575);
DOT 1 (-9250 4525);
DOT 1 (-9250 4725);
DOT 1 (-9250 4675);
DOT 1 (-9250 4875);
DOT 1 (-9250 4825);
DOT 1 (-9250 4775);
DOT 1 (-9250 4925);
DOT 1 (-9250 4975);
DOT 1 (-9250 5025);
DOT 1 (-9250 5125);
DOT 1 (-9250 5075);
DOT 1 (-9250 5225);
DOT 1 (-9250 5175);
DOT 1 (-9250 5275);
DOT 1 (-9250 5375);
DOT 1 (-9250 5325);
DOT 1 (-9250 5525);
DOT 1 (-9250 5475);
DOT 1 (-9250 5425);
DOT 1 (-9250 5625);
DOT 1 (-9250 5575);
DOT 1 (-9250 5775);
DOT 1 (-9250 5725);
DOT 1 (-9250 5675);
DOT 1 (-9250 5825);
DOT 1 (-9250 5875);
DOT 1 (-9250 5925);
DOT 1 (-9250 6025);
DOT 1 (-9250 5975);
DOT 1 (-9250 6075);
DOT 1 (-9250 6125);
DOT 1 (-9250 6175);
DOT 1 (-9250 6225);
DOT 1 (-9250 6275);
DOT 1 (-9250 6325);
DOT 1 (-9250 675);
DOT 1 (-7900 475);
DOT 1 (-7900 525);
DOT 1 (-7900 975);
DOT 1 (-7900 1025);
DOT 1 (-7900 925);
DOT 1 (-7900 875);
DOT 1 (-7900 825);
DOT 1 (-7900 725);
DOT 1 (-7900 775);
DOT 1 (-7900 675);
DOT 1 (-7900 575);
DOT 1 (-7900 625);
DOT 1 (-7900 1325);
DOT 1 (-7900 1125);
DOT 1 (-7900 1525);
DOT 1 (-7900 1475);
DOT 1 (-7900 1425);
DOT 1 (-7900 1375);
DOT 1 (-7900 1275);
DOT 1 (-7900 1225);
DOT 1 (-7900 1175);
DOT 1 (-7900 1075);
DOT 1 (-7900 2025);
DOT 1 (-7900 1975);
DOT 1 (-7900 1875);
DOT 1 (-7900 1925);
DOT 1 (-7900 1825);
DOT 1 (-7900 1775);
DOT 1 (-7900 1725);
DOT 1 (-7900 1675);
DOT 1 (-7900 1575);
DOT 1 (-7900 2075);
DOT 1 (-7900 2575);
DOT 1 (-7900 2475);
DOT 1 (-7900 2525);
DOT 1 (-7900 2425);
DOT 1 (-7900 2375);
DOT 1 (-7900 2325);
DOT 1 (-7900 2225);
DOT 1 (-7900 2275);
DOT 1 (-7900 2175);
DOT 1 (-7900 3075);
DOT 1 (-7900 2775);
DOT 1 (-7900 2825);
DOT 1 (-7900 2725);
DOT 1 (-7900 2675);
DOT 1 (-7900 2625);
DOT 1 (-7900 3575);
DOT 1 (-7900 3525);
DOT 1 (-7900 3475);
DOT 1 (-7900 3375);
DOT 1 (-7900 3425);
DOT 1 (-7900 3325);
DOT 1 (-7900 3275);
DOT 1 (-7900 3225);
DOT 1 (-7900 3175);
DOT 1 (-7900 3125);
DOT 1 (-7900 4075);
DOT 1 (-7900 3925);
DOT 1 (-7900 3975);
DOT 1 (-7900 3875);
DOT 1 (-7900 3825);
DOT 1 (-7900 3775);
DOT 1 (-7900 3725);
DOT 1 (-7900 3625);
DOT 1 (-7900 3675);
DOT 1 (-7900 4125);
DOT 1 (-7900 4625);
DOT 1 (-7900 4525);
DOT 1 (-7900 4575);
DOT 1 (-7900 4475);
DOT 1 (-7900 4425);
DOT 1 (-7900 4375);
DOT 1 (-7900 4275);
DOT 1 (-7900 4325);
DOT 1 (-7900 4175);
DOT 1 (-7900 4225);
DOT 1 (-7900 5075);
DOT 1 (-7900 5125);
DOT 1 (-7900 5025);
DOT 1 (-7900 4975);
DOT 1 (-7900 4925);
DOT 1 (-7900 4875);
DOT 1 (-7900 4775);
DOT 1 (-7900 4825);
DOT 1 (-7900 4725);
DOT 1 (-7900 4675);
DOT 1 (-7900 5625);
DOT 1 (-7900 5575);
DOT 1 (-7900 5525);
DOT 1 (-7900 5425);
DOT 1 (-7900 5475);
DOT 1 (-7900 5325);
DOT 1 (-7900 5375);
DOT 1 (-7900 5275);
DOT 1 (-7900 5225);
DOT 1 (-7900 5175);
DOT 1 (-7900 6125);
DOT 1 (-7900 6075);
DOT 1 (-7900 5975);
DOT 1 (-7900 6025);
DOT 1 (-7900 5925);
DOT 1 (-7900 5825);
DOT 1 (-7900 5775);
DOT 1 (-7900 5675);
DOT 1 (-7900 5725);
DOT 1 (-7900 5875);
DOT 1 (-7900 6175);
DOT 1 (-7900 6325);
DOT 1 (-7900 6225);
DOT 1 (-7900 6275);
DOT 1 (-7900 4025);
DOT 1 (-7900 3025);
DOT 1 (-7900 2975);
DOT 1 (-7900 2925);
DOT 1 (-7900 2875);
DOT 1 (-7900 1625);
DOT 1 (-7900 2125);
DOT 1 (-7725 500);
DOT 1 (-7725 550);
DOT 1 (-7725 600);
DOT 1 (-7725 650);
DOT 1 (-7725 750);
DOT 1 (-7725 700);
DOT 1 (-7725 800);
DOT 1 (-7725 850);
DOT 1 (-7725 900);
DOT 1 (-7725 1000);
DOT 1 (-7725 950);
DOT 1 (-7725 1050);
DOT 1 (-7725 1100);
DOT 1 (-7725 1150);
DOT 1 (-7725 1200);
DOT 1 (-7725 1250);
DOT 1 (-7725 1300);
DOT 1 (-7725 1400);
DOT 1 (-7725 1350);
DOT 1 (-7725 1450);
DOT 1 (-7725 1500);
DOT 1 (-7725 1550);
DOT 1 (-7725 1650);
DOT 1 (-7725 1600);
DOT 1 (-7725 1700);
DOT 1 (-7725 1750);
DOT 1 (-7725 1800);
DOT 1 (-7725 1900);
DOT 1 (-7725 1850);
DOT 1 (-7725 1950);
DOT 1 (-7725 2000);
DOT 1 (-7725 2050);
DOT 1 (-6375 500);
DOT 1 (-6375 550);
DOT 1 (-6375 650);
DOT 1 (-6375 600);
DOT 1 (-6375 700);
DOT 1 (-6375 750);
DOT 1 (-6375 800);
DOT 1 (-6375 850);
DOT 1 (-6375 900);
DOT 1 (-6375 950);
DOT 1 (-6375 1000);
DOT 1 (-6375 1050);
DOT 1 (-6375 1100);
DOT 1 (-6375 1150);
DOT 1 (-6375 1200);
DOT 1 (-6375 1250);
DOT 1 (-6375 1300);
DOT 1 (-6375 1400);
DOT 1 (-6375 1350);
DOT 1 (-6375 1450);
DOT 1 (-6375 1500);
DOT 1 (-6375 1550);
DOT 1 (-6375 1650);
DOT 1 (-6375 1600);
DOT 1 (-6375 1700);
DOT 1 (-6375 1750);
DOT 1 (-6375 1800);
DOT 1 (-6375 1850);
DOT 1 (-6375 1900);
DOT 1 (-6375 1950);
DOT 1 (-6375 2000);
DOT 1 (-6375 2050);
DOT 1 (-7725 2100);
DOT 1 (-7725 2150);
DOT 1 (-7725 2200);
DOT 1 (-7725 2300);
DOT 1 (-7725 2250);
DOT 1 (-7725 2350);
DOT 1 (-7725 2400);
DOT 1 (-7725 2450);
DOT 1 (-7725 2550);
DOT 1 (-7725 2500);
DOT 1 (-7725 2600);
DOT 1 (-7725 2650);
DOT 1 (-7725 2700);
DOT 1 (-7725 2800);
DOT 1 (-7725 2750);
DOT 1 (-7725 2850);
DOT 1 (-7725 2900);
DOT 1 (-7725 2950);
DOT 1 (-7725 3050);
DOT 1 (-7725 3000);
DOT 1 (-7725 3100);
DOT 1 (-7725 3150);
DOT 1 (-7725 3200);
DOT 1 (-7725 3250);
DOT 1 (-7725 3300);
DOT 1 (-7725 3350);
DOT 1 (-7725 3450);
DOT 1 (-7725 3400);
DOT 1 (-7725 3500);
DOT 1 (-7725 3550);
DOT 1 (-7725 3600);
DOT 1 (-7725 3700);
DOT 1 (-7725 3650);
DOT 1 (-7725 3750);
DOT 1 (-7725 3800);
DOT 1 (-7725 3850);
DOT 1 (-7725 3950);
DOT 1 (-7725 3900);
DOT 1 (-7725 4000);
DOT 1 (-7725 4050);
DOT 1 (-7725 4100);
DOT 1 (-6375 2200);
DOT 1 (-6375 2100);
DOT 1 (-6375 2300);
DOT 1 (-6375 2250);
DOT 1 (-6375 2350);
DOT 1 (-6375 2400);
DOT 1 (-6375 2450);
DOT 1 (-6375 2550);
DOT 1 (-6375 2500);
DOT 1 (-6375 2650);
DOT 1 (-6375 2700);
DOT 1 (-6375 2600);
DOT 1 (-6375 2750);
DOT 1 (-6375 2800);
DOT 1 (-6375 2850);
DOT 1 (-6375 2900);
DOT 1 (-6375 2950);
DOT 1 (-6375 3000);
DOT 1 (-6375 3050);
DOT 1 (-6375 3100);
DOT 1 (-6375 3150);
DOT 1 (-6375 3200);
DOT 1 (-6375 3250);
DOT 1 (-6375 3300);
DOT 1 (-6375 3350);
DOT 1 (-6375 3400);
DOT 1 (-6375 3450);
DOT 1 (-6375 3500);
DOT 1 (-6375 3550);
DOT 1 (-6375 3600);
DOT 1 (-6375 3700);
DOT 1 (-6375 3750);
DOT 1 (-6375 3800);
DOT 1 (-6375 3850);
DOT 1 (-6375 3900);
DOT 1 (-6375 3950);
DOT 1 (-6375 4000);
DOT 1 (-6375 4050);
DOT 1 (-6375 4100);
DOT 1 (-7725 4200);
DOT 1 (-7725 4150);
DOT 1 (-7725 4250);
DOT 1 (-7725 4300);
DOT 1 (-7725 4350);
DOT 1 (-7725 4400);
DOT 1 (-7725 4450);
DOT 1 (-7725 4500);
DOT 1 (-7725 4600);
DOT 1 (-7725 4550);
DOT 1 (-7725 4650);
DOT 1 (-7725 4700);
DOT 1 (-7725 4750);
DOT 1 (-7725 4850);
DOT 1 (-7725 4800);
DOT 1 (-7725 4900);
DOT 1 (-7725 4950);
DOT 1 (-7725 5000);
DOT 1 (-7725 5050);
DOT 1 (-7725 5100);
DOT 1 (-7725 5150);
DOT 1 (-7725 5200);
DOT 1 (-7725 5250);
DOT 1 (-7725 5300);
DOT 1 (-7725 5350);
DOT 1 (-7725 5400);
DOT 1 (-7725 5500);
DOT 1 (-7725 5450);
DOT 1 (-7725 5550);
DOT 1 (-7725 5600);
DOT 1 (-7725 5650);
DOT 1 (-7725 5750);
DOT 1 (-7725 5700);
DOT 1 (-7725 5800);
DOT 1 (-7725 5850);
DOT 1 (-7725 5900);
DOT 1 (-7725 5950);
DOT 1 (-7725 6000);
DOT 1 (-7725 6050);
DOT 1 (-7725 6150);
DOT 1 (-7725 6100);
DOT 1 (-6375 4200);
DOT 1 (-6375 4150);
DOT 1 (-6375 4250);
DOT 1 (-6375 4350);
DOT 1 (-6375 4300);
DOT 1 (-6375 4400);
DOT 1 (-6375 4450);
DOT 1 (-6375 4500);
DOT 1 (-6375 4600);
DOT 1 (-6375 4550);
DOT 1 (-6375 4700);
DOT 1 (-6375 4750);
DOT 1 (-6375 4650);
DOT 1 (-6375 4850);
DOT 1 (-6375 4800);
DOT 1 (-6375 4900);
DOT 1 (-6375 4950);
DOT 1 (-6375 5000);
DOT 1 (-6375 5050);
DOT 1 (-6375 5100);
DOT 1 (-6375 5150);
DOT 1 (-6375 5200);
DOT 1 (-6375 5250);
DOT 1 (-6375 5300);
DOT 1 (-6375 5400);
DOT 1 (-6375 5350);
DOT 1 (-6375 5500);
DOT 1 (-6375 5450);
DOT 1 (-6375 5550);
DOT 1 (-6375 5600);
DOT 1 (-6375 5650);
DOT 1 (-6375 5750);
DOT 1 (-6375 5700);
DOT 1 (-6375 5800);
DOT 1 (-6375 5850);
DOT 1 (-6375 5900);
DOT 1 (-6375 5950);
DOT 1 (-6375 6000);
DOT 1 (-6375 6050);
DOT 1 (-6375 6100);
DOT 1 (-6375 6150);
DOT 1 (-7725 6200);
DOT 1 (-7725 6250);
DOT 1 (-6375 6250);
DOT 1 (-6375 6200);
DOT 1 (-6375 2150);
DOT 1 (-6250 525);
DOT 1 (-6250 625);
DOT 1 (-6250 575);
DOT 1 (-6250 675);
DOT 1 (-6250 775);
DOT 1 (-6250 725);
DOT 1 (-6250 875);
DOT 1 (-6250 825);
DOT 1 (-6250 925);
DOT 1 (-6250 1025);
DOT 1 (-6250 975);
DOT 1 (-6250 1175);
DOT 1 (-6250 1125);
DOT 1 (-6250 1075);
DOT 1 (-6250 1275);
DOT 1 (-6250 1225);
DOT 1 (-6250 1425);
DOT 1 (-6250 1375);
DOT 1 (-6250 1325);
DOT 1 (-6250 1525);
DOT 1 (-6250 1475);
DOT 1 (-6250 1575);
DOT 1 (-6250 1625);
DOT 1 (-6250 1675);
DOT 1 (-6250 1775);
DOT 1 (-6250 1725);
DOT 1 (-6250 1825);
DOT 1 (-6250 1925);
DOT 1 (-6250 1875);
DOT 1 (-6250 2025);
DOT 1 (-6250 1975);
DOT 1 (-6250 2075);
DOT 1 (-6250 2175);
DOT 1 (-6250 2125);
DOT 1 (-6250 2325);
DOT 1 (-6250 2275);
DOT 1 (-6250 2225);
DOT 1 (-6250 2425);
DOT 1 (-6250 2375);
DOT 1 (-6250 2575);
DOT 1 (-6250 2525);
DOT 1 (-6250 2475);
DOT 1 (-6250 2675);
DOT 1 (-6250 2625);
DOT 1 (-6250 2725);
DOT 1 (-6250 2825);
DOT 1 (-6250 2775);
DOT 1 (-6250 2925);
DOT 1 (-6250 2875);
DOT 1 (-6250 2975);
DOT 1 (-6250 3075);
DOT 1 (-6250 3025);
DOT 1 (-6250 3175);
DOT 1 (-6250 3125);
DOT 1 (-6250 3225);
DOT 1 (-6250 3325);
DOT 1 (-6250 3275);
DOT 1 (-6250 3475);
DOT 1 (-6250 3425);
DOT 1 (-6250 3375);
DOT 1 (-6250 3575);
DOT 1 (-6250 3525);
DOT 1 (-6250 3725);
DOT 1 (-6250 3625);
DOT 1 (-6250 3825);
DOT 1 (-6250 3775);
DOT 1 (-6250 3875);
DOT 1 (-6250 3975);
DOT 1 (-6250 3925);
DOT 1 (-6250 4075);
DOT 1 (-6250 4025);
DOT 1 (-4900 575);
DOT 1 (-4900 625);
DOT 1 (-4900 675);
DOT 1 (-4900 725);
DOT 1 (-4900 775);
DOT 1 (-4900 875);
DOT 1 (-4900 825);
DOT 1 (-4900 925);
DOT 1 (-4900 1025);
DOT 1 (-4900 975);
DOT 1 (-4900 1175);
DOT 1 (-4900 1075);
DOT 1 (-4900 1125);
DOT 1 (-4900 1275);
DOT 1 (-4900 1225);
DOT 1 (-4900 1325);
DOT 1 (-4900 1375);
DOT 1 (-4900 1425);
DOT 1 (-4900 1475);
DOT 1 (-4900 1525);
DOT 1 (-4900 1675);
DOT 1 (-4900 1625);
DOT 1 (-4900 1575);
DOT 1 (-4900 1775);
DOT 1 (-4900 1725);
DOT 1 (-4900 1825);
DOT 1 (-4900 1875);
DOT 1 (-4900 1925);
DOT 1 (-4900 2025);
DOT 1 (-4900 1975);
DOT 1 (-4900 2075);
DOT 1 (-4900 2125);
DOT 1 (-4900 2175);
DOT 1 (-4900 2275);
DOT 1 (-4900 2225);
DOT 1 (-4900 2325);
DOT 1 (-4900 2425);
DOT 1 (-4900 2375);
DOT 1 (-4900 2575);
DOT 1 (-4900 2525);
DOT 1 (-4900 2475);
DOT 1 (-4900 2625);
DOT 1 (-4900 2675);
DOT 1 (-4900 2725);
DOT 1 (-4900 2825);
DOT 1 (-4900 2775);
DOT 1 (-4900 2875);
DOT 1 (-4900 2925);
DOT 1 (-4900 2975);
DOT 1 (-4900 3075);
DOT 1 (-4900 3025);
DOT 1 (-4900 3175);
DOT 1 (-4900 3125);
DOT 1 (-4900 3225);
DOT 1 (-4900 3275);
DOT 1 (-4900 3325);
DOT 1 (-4900 3375);
DOT 1 (-4900 3425);
DOT 1 (-4900 3475);
DOT 1 (-4900 3525);
DOT 1 (-4900 3575);
DOT 1 (-4900 3675);
DOT 1 (-4900 3625);
DOT 1 (-4900 3725);
DOT 1 (-4900 3825);
DOT 1 (-4900 3775);
DOT 1 (-4900 3875);
DOT 1 (-4900 3925);
DOT 1 (-4900 3975);
DOT 1 (-4900 4075);
DOT 1 (-4900 4025);
DOT 1 (-6250 4125);
DOT 1 (-4900 4125);
DOT 1 (-6250 4175);
DOT 1 (-6250 4225);
DOT 1 (-6250 4325);
DOT 1 (-6250 4375);
DOT 1 (-6250 4275);
DOT 1 (-6250 4475);
DOT 1 (-6250 4425);
DOT 1 (-6250 4575);
DOT 1 (-6250 4625);
DOT 1 (-6250 4525);
DOT 1 (-6250 4725);
DOT 1 (-6250 4675);
DOT 1 (-6250 4775);
DOT 1 (-6250 4825);
DOT 1 (-6250 4875);
DOT 1 (-6250 4925);
DOT 1 (-6250 4975);
DOT 1 (-6250 5025);
DOT 1 (-6250 5075);
DOT 1 (-6250 5125);
DOT 1 (-6250 5175);
DOT 1 (-6250 5225);
DOT 1 (-6250 5275);
DOT 1 (-6250 5375);
DOT 1 (-6250 5525);
DOT 1 (-6250 5475);
DOT 1 (-6250 5425);
DOT 1 (-6250 5625);
DOT 1 (-6250 5575);
DOT 1 (-6250 5775);
DOT 1 (-6250 5725);
DOT 1 (-6250 5675);
DOT 1 (-6250 5875);
DOT 1 (-6250 5825);
DOT 1 (-6250 5925);
DOT 1 (-6250 6025);
DOT 1 (-6250 5975);
DOT 1 (-6250 6125);
DOT 1 (-6250 6075);
DOT 1 (-6250 6175);
DOT 1 (-6250 6275);
DOT 1 (-6250 6225);
DOT 1 (-4900 4175);
DOT 1 (-4900 4225);
DOT 1 (-4900 4325);
DOT 1 (-4900 4275);
DOT 1 (-4900 4375);
DOT 1 (-4900 4475);
DOT 1 (-4900 4425);
DOT 1 (-4900 4625);
DOT 1 (-4900 4575);
DOT 1 (-4900 4525);
DOT 1 (-4900 4675);
DOT 1 (-4900 4725);
DOT 1 (-4900 4775);
DOT 1 (-4900 4825);
DOT 1 (-4900 4875);
DOT 1 (-4900 4975);
DOT 1 (-4900 4925);
DOT 1 (-4900 5025);
DOT 1 (-4900 5125);
DOT 1 (-4900 5075);
DOT 1 (-4900 5225);
DOT 1 (-4900 5175);
DOT 1 (-4900 5275);
DOT 1 (-4900 5325);
DOT 1 (-4900 5375);
DOT 1 (-4900 5475);
DOT 1 (-4900 5425);
DOT 1 (-4900 5525);
DOT 1 (-4900 5575);
DOT 1 (-4900 5625);
DOT 1 (-4900 5725);
DOT 1 (-4900 5675);
DOT 1 (-4900 5775);
DOT 1 (-4900 5875);
DOT 1 (-4900 5825);
DOT 1 (-4900 5925);
DOT 1 (-4900 5975);
DOT 1 (-4900 6025);
DOT 1 (-4900 6075);
DOT 1 (-4900 6175);
DOT 1 (-4900 6225);
DOT 1 (-4900 6275);
DOT 1 (-4750 600);
DOT 1 (-4750 650);
DOT 1 (-4750 750);
DOT 1 (-4750 700);
DOT 1 (-4750 800);
DOT 1 (-4750 850);
DOT 1 (-4750 900);
DOT 1 (-4750 950);
DOT 1 (-4750 1000);
DOT 1 (-4750 1050);
DOT 1 (-4750 1100);
DOT 1 (-4750 1150);
DOT 1 (-4750 1200);
DOT 1 (-4750 1250);
DOT 1 (-4750 1300);
DOT 1 (-4750 1350);
DOT 1 (-4750 1400);
DOT 1 (-4750 1450);
DOT 1 (-4750 1500);
DOT 1 (-4750 1550);
DOT 1 (-4750 1600);
DOT 1 (-4750 1650);
DOT 1 (-4750 1700);
DOT 1 (-4750 1750);
DOT 1 (-4750 1800);
DOT 1 (-4750 1850);
DOT 1 (-4750 1900);
DOT 1 (-4750 1950);
DOT 1 (-4750 2000);
DOT 1 (-4750 2050);
DOT 1 (-4750 2100);
DOT 1 (-4750 2150);
DOT 1 (-4750 2200);
DOT 1 (-4750 2250);
DOT 1 (-4750 2300);
DOT 1 (-4750 2350);
DOT 1 (-4750 2400);
DOT 1 (-4750 2450);
DOT 1 (-4750 2500);
DOT 1 (-4750 2550);
DOT 1 (-4750 2600);
DOT 1 (-4750 2650);
DOT 1 (-4750 2700);
DOT 1 (-4750 2750);
DOT 1 (-4750 2800);
DOT 1 (-4750 2850);
DOT 1 (-4750 2900);
DOT 1 (-4750 2950);
DOT 1 (-4750 3000);
DOT 1 (-4750 3050);
DOT 1 (-4750 3100);
DOT 1 (-4750 3150);
DOT 1 (-4750 3200);
DOT 1 (-4750 3250);
DOT 1 (-4750 3300);
DOT 1 (-4750 3350);
DOT 1 (-4750 3400);
DOT 1 (-4750 3450);
DOT 1 (-4750 3500);
DOT 1 (-4750 3550);
DOT 1 (-4750 3600);
DOT 1 (-4750 3650);
DOT 1 (-4750 3700);
DOT 1 (-4750 3750);
DOT 1 (-4750 3800);
DOT 1 (-4750 3850);
DOT 1 (-4750 3900);
DOT 1 (-4750 3950);
DOT 1 (-4750 4000);
DOT 1 (-4750 4050);
DOT 1 (-4750 4100);
DOT 1 (-4750 4150);
DOT 1 (-4750 4200);
DOT 1 (-4750 4250);
DOT 1 (-4750 4300);
DOT 1 (-4750 4350);
DOT 1 (-4750 4400);
DOT 1 (-4750 4450);
DOT 1 (-4750 4500);
DOT 1 (-4750 4550);
DOT 1 (-4750 4600);
DOT 1 (-4750 4650);
DOT 1 (-4750 4700);
DOT 1 (-4750 4750);
DOT 1 (-4750 4800);
DOT 1 (-4750 4850);
DOT 1 (-4750 4900);
DOT 1 (-4750 4950);
DOT 1 (-4750 5000);
DOT 1 (-4750 5050);
DOT 1 (-4750 5100);
DOT 1 (-4750 5150);
DOT 1 (-4750 5200);
DOT 1 (-4750 5250);
DOT 1 (-4750 5300);
DOT 1 (-4750 5350);
DOT 1 (-4750 5400);
DOT 1 (-4750 5450);
DOT 1 (-4750 5500);
DOT 1 (-4750 5550);
DOT 1 (-4750 5600);
DOT 1 (-4750 5650);
DOT 1 (-4750 5700);
DOT 1 (-4750 5750);
DOT 1 (-4750 5800);
DOT 1 (-4750 5850);
DOT 1 (-4750 5900);
DOT 1 (-4750 5950);
DOT 1 (-4750 6000);
DOT 1 (-4750 6050);
DOT 1 (-4750 6100);
DOT 1 (-4750 6150);
DOT 1 (-4750 6200);
DOT 1 (-4750 6250);
DOT 1 (-4750 6300);
DOT 1 (-4750 6350);
DOT 1 (-3400 600);
DOT 1 (-3400 650);
DOT 1 (-3400 700);
DOT 1 (-3400 750);
DOT 1 (-3400 800);
DOT 1 (-3400 850);
DOT 1 (-3400 900);
DOT 1 (-3400 950);
DOT 1 (-3400 1000);
DOT 1 (-3400 1050);
DOT 1 (-3400 1100);
DOT 1 (-3400 1150);
DOT 1 (-3400 1200);
DOT 1 (-3400 1250);
DOT 1 (-3400 1300);
DOT 1 (-3400 1400);
DOT 1 (-3400 1350);
DOT 1 (-3400 1450);
DOT 1 (-3400 1500);
DOT 1 (-3400 1550);
DOT 1 (-3400 1600);
DOT 1 (-3400 1650);
DOT 1 (-3400 1700);
DOT 1 (-3400 1750);
DOT 1 (-3400 1800);
DOT 1 (-3400 1900);
DOT 1 (-3400 1850);
DOT 1 (-3400 1950);
DOT 1 (-3400 2000);
DOT 1 (-3400 2050);
DOT 1 (-3400 2100);
DOT 1 (-3400 2150);
DOT 1 (-3400 2200);
DOT 1 (-3400 2250);
DOT 1 (-3400 2300);
DOT 1 (-3400 2350);
DOT 1 (-3400 2400);
DOT 1 (-3400 2450);
DOT 1 (-3400 2500);
DOT 1 (-3400 2550);
DOT 1 (-3400 2600);
DOT 1 (-3400 2650);
DOT 1 (-3400 2700);
DOT 1 (-3400 2800);
DOT 1 (-3400 2750);
DOT 1 (-3400 2850);
DOT 1 (-3400 2900);
DOT 1 (-3400 2950);
DOT 1 (-3400 3000);
DOT 1 (-3400 3050);
DOT 1 (-3400 3100);
DOT 1 (-3400 3150);
DOT 1 (-3400 3200);
DOT 1 (-3400 3250);
DOT 1 (-3400 3300);
DOT 1 (-3400 3450);
DOT 1 (-3400 3400);
DOT 1 (-3400 3500);
DOT 1 (-3400 3550);
DOT 1 (-3400 3600);
DOT 1 (-3400 3650);
DOT 1 (-3400 3700);
DOT 1 (-3400 3750);
DOT 1 (-3400 3800);
DOT 1 (-3400 3850);
DOT 1 (-3400 3950);
DOT 1 (-3400 3900);
DOT 1 (-3400 4000);
DOT 1 (-3400 4050);
DOT 1 (-3400 4100);
DOT 1 (-3400 4150);
DOT 1 (-3400 4200);
DOT 1 (-3400 4250);
DOT 1 (-3400 4300);
DOT 1 (-3400 4350);
DOT 1 (-3400 4400);
DOT 1 (-3400 4450);
DOT 1 (-3400 4500);
DOT 1 (-3400 4550);
DOT 1 (-3400 4600);
DOT 1 (-3400 4650);
DOT 1 (-3400 4700);
DOT 1 (-3400 4750);
DOT 1 (-3400 4850);
DOT 1 (-3400 4800);
DOT 1 (-3400 4900);
DOT 1 (-3400 4950);
DOT 1 (-3400 5000);
DOT 1 (-3400 5050);
DOT 1 (-3400 5100);
DOT 1 (-3400 5150);
DOT 1 (-3400 5200);
DOT 1 (-3400 5250);
DOT 1 (-3400 5300);
DOT 1 (-3400 5350);
DOT 1 (-3400 5400);
DOT 1 (-3400 5450);
DOT 1 (-3400 5500);
DOT 1 (-3400 5550);
DOT 1 (-3400 5600);
DOT 1 (-3400 5650);
DOT 1 (-3400 5700);
DOT 1 (-3400 5750);
DOT 1 (-3400 5800);
DOT 1 (-3400 5850);
DOT 1 (-3400 5900);
DOT 1 (-3400 6000);
DOT 1 (-3400 5950);
DOT 1 (-3400 6050);
DOT 1 (-3400 6100);
DOT 1 (-3400 6150);
DOT 1 (-3400 6200);
DOT 1 (-3400 6250);
DOT 1 (-3400 6300);
DOT 1 (-3400 6350);
DOT 1 (-6375 3650);
DOT 1 (-6250 3675);
DOT 1 (-3400 3350);
DOT 1 (-3250 550);
DOT 1 (-3250 600);
DOT 1 (-3250 650);
DOT 1 (-3250 700);
DOT 1 (-3250 750);
DOT 1 (-3250 800);
DOT 1 (-3250 850);
DOT 1 (-3250 900);
DOT 1 (-3250 950);
DOT 1 (-3250 1000);
DOT 1 (-3250 1050);
DOT 1 (-3250 1100);
DOT 1 (-3250 1150);
DOT 1 (-3250 1300);
DOT 1 (-3250 1250);
DOT 1 (-3250 1200);
DOT 1 (-3250 1350);
DOT 1 (-3250 1400);
DOT 1 (-3250 1550);
DOT 1 (-3250 1500);
DOT 1 (-3250 1450);
DOT 1 (-3250 1600);
DOT 1 (-3250 1650);
DOT 1 (-3250 1700);
DOT 1 (-3250 1800);
DOT 1 (-3250 1750);
DOT 1 (-3250 1850);
DOT 1 (-3250 1900);
DOT 1 (-3250 1950);
DOT 1 (-3250 2050);
DOT 1 (-3250 2000);
DOT 1 (-3250 2100);
DOT 1 (-3250 2150);
DOT 1 (-3250 2200);
DOT 1 (-3250 2250);
DOT 1 (-3250 2300);
DOT 1 (-3250 2350);
DOT 1 (-3250 2400);
DOT 1 (-3250 2450);
DOT 1 (-3250 2500);
DOT 1 (-3250 2550);
DOT 1 (-3250 2600);
DOT 1 (-3250 2650);
DOT 1 (-3250 2700);
DOT 1 (-3250 2750);
DOT 1 (-3250 2800);
DOT 1 (-3250 2850);
DOT 1 (-3250 2900);
DOT 1 (-3250 2950);
DOT 1 (-3250 3000);
DOT 1 (-3250 3050);
DOT 1 (-3250 3100);
DOT 1 (-3250 3150);
DOT 1 (-3250 3200);
DOT 1 (-3250 3350);
DOT 1 (-3250 3300);
DOT 1 (-3250 3250);
DOT 1 (-3250 3400);
DOT 1 (-3250 3450);
DOT 1 (-3250 3600);
DOT 1 (-3250 3550);
DOT 1 (-3250 3500);
DOT 1 (-3250 3650);
DOT 1 (-3250 3700);
DOT 1 (-3250 3750);
DOT 1 (-3250 3850);
DOT 1 (-3250 3800);
DOT 1 (-3250 3900);
DOT 1 (-3250 3950);
DOT 1 (-3250 4000);
DOT 1 (-3250 4100);
DOT 1 (-3250 4050);
DOT 1 (-1925 600);
DOT 1 (-1925 700);
DOT 1 (-1925 800);
DOT 1 (-1925 900);
DOT 1 (-1925 1000);
DOT 1 (-1925 1050);
DOT 1 (-1925 1100);
DOT 1 (-1925 1150);
DOT 1 (-1925 1200);
DOT 1 (-1925 1250);
DOT 1 (-1925 1300);
DOT 1 (-1925 1400);
DOT 1 (-1925 1350);
DOT 1 (-1925 1450);
DOT 1 (-1925 1500);
DOT 1 (-1925 1550);
DOT 1 (-1925 1600);
DOT 1 (-1925 1650);
DOT 1 (-1925 1700);
DOT 1 (-1925 1750);
DOT 1 (-1925 1800);
DOT 1 (-1925 1900);
DOT 1 (-1925 1850);
DOT 1 (-1925 1950);
DOT 1 (-1925 2000);
DOT 1 (-1925 2050);
DOT 1 (-1925 2100);
DOT 1 (-1925 2150);
DOT 1 (-1925 2200);
DOT 1 (-1925 2300);
DOT 1 (-1925 2250);
DOT 1 (-1925 2350);
DOT 1 (-1925 2400);
DOT 1 (-1925 2450);
DOT 1 (-1925 2550);
DOT 1 (-1925 2500);
DOT 1 (-1925 2600);
DOT 1 (-1925 2650);
DOT 1 (-1925 2700);
DOT 1 (-1925 2800);
DOT 1 (-1925 2750);
DOT 1 (-1925 2850);
DOT 1 (-1925 2900);
DOT 1 (-1925 2950);
DOT 1 (-1925 3050);
DOT 1 (-1925 3000);
DOT 1 (-1925 3100);
DOT 1 (-1925 3150);
DOT 1 (-1925 3200);
DOT 1 (-1925 3250);
DOT 1 (-1925 3300);
DOT 1 (-1925 3350);
DOT 1 (-1925 3450);
DOT 1 (-1925 3400);
DOT 1 (-1925 3500);
DOT 1 (-1925 3550);
DOT 1 (-1925 3600);
DOT 1 (-1925 3650);
DOT 1 (-1925 3700);
DOT 1 (-1925 3750);
DOT 1 (-1925 3800);
DOT 1 (-1925 3850);
DOT 1 (-1925 3950);
DOT 1 (-1925 3900);
DOT 1 (-1925 4000);
DOT 1 (-1925 4050);
DOT 1 (-1925 4100);
DOT 1 (-3250 4150);
DOT 1 (-3250 4200);
DOT 1 (-3250 4250);
DOT 1 (-3250 4350);
DOT 1 (-3250 4300);
DOT 1 (-3250 4400);
DOT 1 (-3250 4450);
DOT 1 (-3250 4500);
DOT 1 (-3250 4550);
DOT 1 (-3250 4600);
DOT 1 (-3250 4650);
DOT 1 (-3250 4700);
DOT 1 (-3250 4750);
DOT 1 (-3250 4800);
DOT 1 (-3250 4850);
DOT 1 (-3250 4900);
DOT 1 (-3250 4950);
DOT 1 (-3250 5000);
DOT 1 (-3250 5050);
DOT 1 (-3250 5100);
DOT 1 (-3250 5150);
DOT 1 (-3250 5200);
DOT 1 (-3250 5250);
DOT 1 (-3250 5400);
DOT 1 (-3250 5350);
DOT 1 (-3250 5300);
DOT 1 (-3250 5450);
DOT 1 (-3250 5500);
DOT 1 (-3250 5650);
DOT 1 (-3250 5600);
DOT 1 (-3250 5550);
DOT 1 (-3250 5700);
DOT 1 (-3250 5750);
DOT 1 (-3250 5900);
DOT 1 (-3250 5850);
DOT 1 (-3250 5800);
DOT 1 (-3250 5950);
DOT 1 (-3250 6000);
DOT 1 (-3250 6050);
DOT 1 (-3250 6150);
DOT 1 (-3250 6100);
DOT 1 (-3250 6250);
DOT 1 (-3250 6200);
DOT 1 (-3250 6300);
DOT 1 (-3250 6350);
DOT 1 (-1925 4200);
DOT 1 (-1925 4150);
DOT 1 (-1925 4250);
DOT 1 (-1925 4300);
DOT 1 (-1925 4350);
DOT 1 (-1925 4400);
DOT 1 (-1925 4450);
DOT 1 (-1925 4500);
DOT 1 (-1925 4600);
DOT 1 (-1925 4550);
DOT 1 (-1925 4650);
DOT 1 (-1925 4700);
DOT 1 (-1925 4750);
DOT 1 (-1925 4850);
DOT 1 (-1925 4800);
DOT 1 (-1925 4900);
DOT 1 (-1925 4950);
DOT 1 (-1925 5000);
DOT 1 (-1925 5100);
DOT 1 (-1925 5050);
DOT 1 (-1925 5150);
DOT 1 (-1925 5200);
DOT 1 (-1925 5250);
DOT 1 (-1925 5300);
DOT 1 (-1925 5350);
DOT 1 (-1925 5400);
DOT 1 (-1925 5500);
DOT 1 (-1925 5450);
DOT 1 (-1925 5550);
DOT 1 (-1925 5600);
DOT 1 (-1925 5650);
DOT 1 (-1925 5700);
DOT 1 (-1925 5750);
DOT 1 (-1925 5800);
DOT 1 (-1925 5850);
DOT 1 (-1925 5900);
DOT 1 (-1925 6000);
DOT 1 (-1925 5950);
DOT 1 (-1925 6050);
DOT 1 (-1925 6100);
DOT 1 (-1925 6150);
DOT 1 (-1925 6250);
DOT 1 (-1925 6200);
DOT 1 (-1925 6300);
DOT 1 (-1925 6350);
DOT 1 (-1925 6400);
DOT 1 (-1925 550);
DOT 1 (-1925 650);
DOT 1 (-1925 750);
DOT 1 (-1925 850);
DOT 1 (-1925 950);
DOT 1 (-4900 6125);
DOT 1 (-1625 650);
DOT 1 (-1625 750);
DOT 1 (-1625 700);
DOT 1 (-1625 800);
DOT 1 (-1625 850);
DOT 1 (-1625 900);
DOT 1 (-1625 1000);
DOT 1 (-1625 950);
DOT 1 (-1625 1050);
DOT 1 (-1625 1100);
DOT 1 (-1625 1150);
DOT 1 (-1625 1200);
DOT 1 (-1625 1250);
DOT 1 (-1625 1300);
DOT 1 (-1625 1400);
DOT 1 (-1625 1350);
DOT 1 (-1625 1450);
DOT 1 (-1625 1500);
DOT 1 (-1625 1550);
DOT 1 (-1625 1650);
DOT 1 (-1625 1600);
DOT 1 (-1625 1700);
DOT 1 (-1625 1750);
DOT 1 (-1625 1800);
DOT 1 (-1625 1900);
DOT 1 (-1625 1850);
DOT 1 (-1625 1950);
DOT 1 (-1625 2000);
DOT 1 (-1625 2050);
DOT 1 (-300 550);
DOT 1 (-300 650);
DOT 1 (-300 600);
DOT 1 (-300 750);
DOT 1 (-300 700);
DOT 1 (-300 800);
DOT 1 (-300 900);
DOT 1 (-300 850);
DOT 1 (-300 950);
DOT 1 (-300 1000);
DOT 1 (-300 1050);
DOT 1 (-300 1150);
DOT 1 (-300 1100);
DOT 1 (-300 1300);
DOT 1 (-300 1250);
DOT 1 (-300 1200);
DOT 1 (-300 1400);
DOT 1 (-300 1350);
DOT 1 (-300 1500);
DOT 1 (-300 1550);
DOT 1 (-300 1450);
DOT 1 (-300 1650);
DOT 1 (-300 1600);
DOT 1 (-300 1700);
DOT 1 (-300 1800);
DOT 1 (-300 1750);
DOT 1 (-300 1900);
DOT 1 (-300 1850);
DOT 1 (-300 1950);
DOT 1 (-300 2050);
DOT 1 (-300 2000);
DOT 1 (-1625 2100);
DOT 1 (-1625 2150);
DOT 1 (-1625 2200);
DOT 1 (-1625 2300);
DOT 1 (-1625 2250);
DOT 1 (-1625 2350);
DOT 1 (-1625 2400);
DOT 1 (-1625 2450);
DOT 1 (-1625 2550);
DOT 1 (-1625 2500);
DOT 1 (-1625 2600);
DOT 1 (-1625 2650);
DOT 1 (-1625 2700);
DOT 1 (-1625 2800);
DOT 1 (-1625 2750);
DOT 1 (-1625 2850);
DOT 1 (-1625 2900);
DOT 1 (-1625 2950);
DOT 1 (-1625 3050);
DOT 1 (-1625 3000);
DOT 1 (-1625 3100);
DOT 1 (-1625 3150);
DOT 1 (-1625 3200);
DOT 1 (-1625 3250);
DOT 1 (-1625 3300);
DOT 1 (-1625 3350);
DOT 1 (-1625 3450);
DOT 1 (-1625 3400);
DOT 1 (-1625 3500);
DOT 1 (-1625 3550);
DOT 1 (-1625 3600);
DOT 1 (-1625 3700);
DOT 1 (-1625 3650);
DOT 1 (-1625 3750);
DOT 1 (-1625 3800);
DOT 1 (-1625 3850);
DOT 1 (-1625 3950);
DOT 1 (-1625 3900);
DOT 1 (-1625 4000);
DOT 1 (-1625 4050);
DOT 1 (-1625 4100);
DOT 1 (-300 2200);
DOT 1 (-300 2150);
DOT 1 (-300 2100);
DOT 1 (-300 2300);
DOT 1 (-300 2250);
DOT 1 (-300 2450);
DOT 1 (-300 2400);
DOT 1 (-300 2350);
DOT 1 (-300 2500);
DOT 1 (-300 2550);
DOT 1 (-300 2650);
DOT 1 (-300 2700);
DOT 1 (-300 2600);
DOT 1 (-300 2750);
DOT 1 (-300 2800);
DOT 1 (-300 2850);
DOT 1 (-300 2950);
DOT 1 (-300 2900);
DOT 1 (-300 3000);
DOT 1 (-300 3050);
DOT 1 (-300 3100);
DOT 1 (-300 3200);
DOT 1 (-300 3150);
DOT 1 (-300 3300);
DOT 1 (-300 3350);
DOT 1 (-300 3250);
DOT 1 (-300 3450);
DOT 1 (-300 3400);
DOT 1 (-300 3550);
DOT 1 (-300 3600);
DOT 1 (-300 3500);
DOT 1 (-300 3700);
DOT 1 (-300 3650);
DOT 1 (-300 3750);
DOT 1 (-300 3850);
DOT 1 (-300 3800);
DOT 1 (-300 3950);
DOT 1 (-300 3900);
DOT 1 (-300 4000);
DOT 1 (-300 4100);
DOT 1 (-300 4050);
DOT 1 (-1625 4200);
DOT 1 (-1625 4150);
DOT 1 (-1625 4250);
DOT 1 (-1625 4300);
DOT 1 (-1625 4350);
DOT 1 (-1625 4400);
DOT 1 (-1625 4450);
DOT 1 (-1625 4500);
DOT 1 (-1625 4600);
DOT 1 (-1625 4550);
DOT 1 (-1625 4650);
DOT 1 (-1625 4700);
DOT 1 (-1625 4750);
DOT 1 (-1625 4850);
DOT 1 (-1625 4800);
DOT 1 (-1625 4900);
DOT 1 (-1625 4950);
DOT 1 (-1625 5000);
DOT 1 (-1625 5100);
DOT 1 (-1625 5050);
DOT 1 (-1625 5150);
DOT 1 (-1625 5200);
DOT 1 (-1625 5250);
DOT 1 (-1625 5300);
DOT 1 (-1625 5350);
DOT 1 (-1625 5400);
DOT 1 (-1625 5500);
DOT 1 (-1625 5450);
DOT 1 (-1625 5550);
DOT 1 (-1625 5600);
DOT 1 (-1625 5650);
DOT 1 (-1625 5750);
DOT 1 (-1625 5700);
DOT 1 (-1625 5800);
DOT 1 (-1625 5850);
DOT 1 (-1625 5900);
DOT 1 (-1625 6000);
DOT 1 (-1625 5950);
DOT 1 (-1625 6050);
DOT 1 (-1625 6100);
DOT 1 (-1625 6150);
DOT 1 (-300 4200);
DOT 1 (-300 4150);
DOT 1 (-300 4250);
DOT 1 (-300 4350);
DOT 1 (-300 4300);
DOT 1 (-300 4500);
DOT 1 (-300 4450);
DOT 1 (-300 4400);
DOT 1 (-300 4550);
DOT 1 (-300 4600);
DOT 1 (-300 4700);
DOT 1 (-300 4750);
DOT 1 (-300 4650);
DOT 1 (-300 4800);
DOT 1 (-300 4850);
DOT 1 (-300 4900);
DOT 1 (-300 5000);
DOT 1 (-300 4950);
DOT 1 (-300 5050);
DOT 1 (-300 5100);
DOT 1 (-300 5150);
DOT 1 (-300 5250);
DOT 1 (-300 5200);
DOT 1 (-300 5350);
DOT 1 (-300 5400);
DOT 1 (-300 5300);
DOT 1 (-300 5500);
DOT 1 (-300 5450);
DOT 1 (-300 5600);
DOT 1 (-300 5650);
DOT 1 (-300 5550);
DOT 1 (-300 5750);
DOT 1 (-300 5700);
DOT 1 (-300 5850);
DOT 1 (-300 5900);
DOT 1 (-300 5800);
DOT 1 (-300 6000);
DOT 1 (-300 5950);
DOT 1 (-300 6050);
DOT 1 (-300 6150);
DOT 1 (-300 6100);
DOT 1 (-1625 6250);
DOT 1 (-1625 6200);
DOT 1 (-1625 6300);
DOT 1 (-1625 6350);
DOT 1 (-1625 6400);
DOT 1 (-300 6250);
DOT 1 (-300 6200);
DOT 1 (-300 6300);
DOT 1 (-300 6400);
DOT 1 (-300 6350);
DOT 1 (-6250 5325);
DOT 1 (-1625 600);
DOT 1 (-1625 550);
QUIT
